FILE_TYPE = MACRO_DRAWING;
SET COLOR_WIRE YELLOW;
SET COLOR_PROP ORANGE;
SET COLOR_DOT WHITE;
SET COLOR_ARC YELLOW;
SET COLOR_BODY GREEN;
SET COLOR_NOTE PURPLE;
SET PROP_DISPLAY VALUE;
SET PAGE_NUMBER P97;
FORCEADD OFFPAGE..5
(-8050 2025);
FORCEPROP 2 LAST $XR0 37 
J 0
(-8304 2025);
DISPLAY 0.638298 (-8304 2025);
PAINT MONO (-8304 2025);
FORCEPROP 2 LAST CDS_LIB mstr_standard
J 0
(-8050 2025);
DISPLAY 0.808511 (-8050 2025);
DISPLAY INVISIBLE (-8050 2025);
FORCEPROP 1 LAST OFFPAGE TRUE
J 0
(-7725 1900);
DISPLAY 0.872340 (-7725 1900);
PAINT GREEN (-7725 1900);
DISPLAY INVISIBLE (-7725 1900);
FORCEPROP 1 LAST COMMENT_BODY TRUE
J 0
(-7950 1950);
DISPLAY 0.872340 (-7950 1950);
PAINT GREEN (-7950 1950);
DISPLAY INVISIBLE (-7950 1950);
FORCEPROP 2 LAST PATH I1
J 0
(-8250 2075);
DISPLAY 1.021277 (-8250 2075);
DISPLAY INVISIBLE (-8250 2075);
FORCEADD OFFPAGE..6
(-8050 3675);
FORCEPROP 2 LAST $XR0 37 
J 0
(-8329 3675);
DISPLAY 0.638298 (-8329 3675);
PAINT MONO (-8329 3675);
FORCEPROP 2 LAST CDS_LIB mstr_standard
J 0
(-8050 3675);
DISPLAY 0.723404 (-8050 3675);
PAINT MONO (-8050 3675);
DISPLAY INVISIBLE (-8050 3675);
FORCEPROP 1 LAST OFFPAGE TRUE
J 0
(-7725 3550);
DISPLAY 0.872340 (-7725 3550);
PAINT GREEN (-7725 3550);
DISPLAY INVISIBLE (-7725 3550);
FORCEPROP 1 LAST COMMENT_BODY TRUE
J 0
(-7950 3600);
DISPLAY 0.872340 (-7950 3600);
PAINT GREEN (-7950 3600);
DISPLAY INVISIBLE (-7950 3600);
FORCEPROP 2 LAST PATH I10
J 0
(-8325 3725);
DISPLAY 1.021277 (-8325 3725);
DISPLAY INVISIBLE (-8325 3725);
FORCEADD TAP..1
(-5750 4175);
FORCEPROP 3 LASTPIN (-5800 4175) SIG_NAME M_A_CPU1_SA_DQ<5>
J 0
(-5790 4185);
DISPLAY 0.659574 (-5790 4185);
PAINT MONO (-5790 4185);
DISPLAY INVISIBLE (-5790 4185);
FORCEPROP 1 LASTPIN (-5800 4175) BN 5
J 0
(-5812 4183);
DISPLAY 0.489362 (-5812 4183);
PAINT GREEN (-5812 4183);
FORCEPROP 2 LAST CDS_LIB mstr_standard
J 0
(-5750 4175);
DISPLAY 0.723404 (-5750 4175);
PAINT MONO (-5750 4175);
DISPLAY INVISIBLE (-5750 4175);
FORCEPROP 1 LAST BODY_TYPE PLUMBING
J 0
(-5750 4225);
DISPLAY 0.872340 (-5750 4225);
PAINT GREEN (-5750 4225);
DISPLAY INVISIBLE (-5750 4225);
FORCEPROP 1 LAST HDL_TAP TRUE
J 0
(-5425 4050);
DISPLAY 0.872340 (-5425 4050);
DISPLAY INVISIBLE (-5425 4050);
FORCEPROP 1 LAST PATH I100
J 0
(-5752 4175);
DISPLAY 0.872340 (-5752 4175);
PAINT GREEN (-5752 4175);
DISPLAY INVISIBLE (-5752 4175);
FORCEADD TAP..1
(-5750 4325);
FORCEPROP 3 LASTPIN (-5800 4325) SIG_NAME M_A_CPU1_SA_DQ<8>
J 0
(-5790 4335);
DISPLAY 0.659574 (-5790 4335);
PAINT MONO (-5790 4335);
DISPLAY INVISIBLE (-5790 4335);
FORCEPROP 1 LASTPIN (-5800 4325) BN 8
J 0
(-5812 4333);
DISPLAY 0.489362 (-5812 4333);
PAINT GREEN (-5812 4333);
FORCEPROP 2 LAST CDS_LIB mstr_standard
J 0
(-5750 4325);
DISPLAY 0.723404 (-5750 4325);
PAINT MONO (-5750 4325);
DISPLAY INVISIBLE (-5750 4325);
FORCEPROP 1 LAST BODY_TYPE PLUMBING
J 0
(-5750 4375);
DISPLAY 0.872340 (-5750 4375);
PAINT GREEN (-5750 4375);
DISPLAY INVISIBLE (-5750 4375);
FORCEPROP 1 LAST HDL_TAP TRUE
J 0
(-5425 4200);
DISPLAY 0.872340 (-5425 4200);
DISPLAY INVISIBLE (-5425 4200);
FORCEPROP 1 LAST PATH I101
J 0
(-5752 4325);
DISPLAY 0.872340 (-5752 4325);
PAINT GREEN (-5752 4325);
DISPLAY INVISIBLE (-5752 4325);
FORCEADD TAP..1
(-5750 4375);
FORCEPROP 3 LASTPIN (-5800 4375) SIG_NAME M_A_CPU1_SA_DQ<9>
J 0
(-5790 4385);
DISPLAY 0.659574 (-5790 4385);
PAINT MONO (-5790 4385);
DISPLAY INVISIBLE (-5790 4385);
FORCEPROP 1 LASTPIN (-5800 4375) BN 9
J 0
(-5812 4383);
DISPLAY 0.489362 (-5812 4383);
PAINT GREEN (-5812 4383);
FORCEPROP 2 LAST CDS_LIB mstr_standard
J 0
(-5750 4375);
DISPLAY 0.723404 (-5750 4375);
PAINT MONO (-5750 4375);
DISPLAY INVISIBLE (-5750 4375);
FORCEPROP 1 LAST BODY_TYPE PLUMBING
J 0
(-5750 4425);
DISPLAY 0.872340 (-5750 4425);
PAINT GREEN (-5750 4425);
DISPLAY INVISIBLE (-5750 4425);
FORCEPROP 1 LAST HDL_TAP TRUE
J 0
(-5425 4250);
DISPLAY 0.872340 (-5425 4250);
DISPLAY INVISIBLE (-5425 4250);
FORCEPROP 1 LAST PATH I102
J 0
(-5752 4375);
DISPLAY 0.872340 (-5752 4375);
PAINT GREEN (-5752 4375);
DISPLAY INVISIBLE (-5752 4375);
FORCEADD TAP..1
(-5750 4275);
FORCEPROP 3 LASTPIN (-5800 4275) SIG_NAME M_A_CPU1_SA_DQ<7>
J 0
(-5790 4285);
DISPLAY 0.659574 (-5790 4285);
PAINT MONO (-5790 4285);
DISPLAY INVISIBLE (-5790 4285);
FORCEPROP 1 LASTPIN (-5800 4275) BN 7
J 0
(-5812 4283);
DISPLAY 0.489362 (-5812 4283);
PAINT GREEN (-5812 4283);
FORCEPROP 2 LAST CDS_LIB mstr_standard
J 0
(-5750 4275);
DISPLAY 0.723404 (-5750 4275);
PAINT MONO (-5750 4275);
DISPLAY INVISIBLE (-5750 4275);
FORCEPROP 1 LAST BODY_TYPE PLUMBING
J 0
(-5750 4325);
DISPLAY 0.872340 (-5750 4325);
PAINT GREEN (-5750 4325);
DISPLAY INVISIBLE (-5750 4325);
FORCEPROP 1 LAST HDL_TAP TRUE
J 0
(-5425 4150);
DISPLAY 0.872340 (-5425 4150);
DISPLAY INVISIBLE (-5425 4150);
FORCEPROP 1 LAST PATH I103
J 0
(-5752 4275);
DISPLAY 0.872340 (-5752 4275);
PAINT GREEN (-5752 4275);
DISPLAY INVISIBLE (-5752 4275);
FORCEADD TAP..1
(-5750 4525);
FORCEPROP 3 LASTPIN (-5800 4525) SIG_NAME M_A_CPU1_SA_DQ<12>
J 0
(-5790 4535);
DISPLAY 0.659574 (-5790 4535);
PAINT MONO (-5790 4535);
DISPLAY INVISIBLE (-5790 4535);
FORCEPROP 1 LASTPIN (-5800 4525) BN 12
J 0
(-5812 4533);
DISPLAY 0.489362 (-5812 4533);
PAINT GREEN (-5812 4533);
FORCEPROP 2 LAST CDS_LIB mstr_standard
J 0
(-5750 4525);
DISPLAY 0.723404 (-5750 4525);
PAINT MONO (-5750 4525);
DISPLAY INVISIBLE (-5750 4525);
FORCEPROP 1 LAST BODY_TYPE PLUMBING
J 0
(-5750 4575);
DISPLAY 0.872340 (-5750 4575);
PAINT GREEN (-5750 4575);
DISPLAY INVISIBLE (-5750 4575);
FORCEPROP 1 LAST HDL_TAP TRUE
J 0
(-5425 4400);
DISPLAY 0.872340 (-5425 4400);
DISPLAY INVISIBLE (-5425 4400);
FORCEPROP 1 LAST PATH I104
J 0
(-5752 4525);
DISPLAY 0.872340 (-5752 4525);
PAINT GREEN (-5752 4525);
DISPLAY INVISIBLE (-5752 4525);
FORCEADD TAP..1
(-5750 4475);
FORCEPROP 3 LASTPIN (-5800 4475) SIG_NAME M_A_CPU1_SA_DQ<11>
J 0
(-5790 4485);
DISPLAY 0.659574 (-5790 4485);
PAINT MONO (-5790 4485);
DISPLAY INVISIBLE (-5790 4485);
FORCEPROP 1 LASTPIN (-5800 4475) BN 11
J 0
(-5812 4483);
DISPLAY 0.489362 (-5812 4483);
PAINT GREEN (-5812 4483);
FORCEPROP 2 LAST CDS_LIB mstr_standard
J 0
(-5750 4475);
DISPLAY 0.723404 (-5750 4475);
PAINT MONO (-5750 4475);
DISPLAY INVISIBLE (-5750 4475);
FORCEPROP 1 LAST BODY_TYPE PLUMBING
J 0
(-5750 4525);
DISPLAY 0.872340 (-5750 4525);
PAINT GREEN (-5750 4525);
DISPLAY INVISIBLE (-5750 4525);
FORCEPROP 1 LAST HDL_TAP TRUE
J 0
(-5425 4350);
DISPLAY 0.872340 (-5425 4350);
DISPLAY INVISIBLE (-5425 4350);
FORCEPROP 1 LAST PATH I105
J 0
(-5752 4475);
DISPLAY 0.872340 (-5752 4475);
PAINT GREEN (-5752 4475);
DISPLAY INVISIBLE (-5752 4475);
FORCEADD TAP..1
(-5750 4425);
FORCEPROP 3 LASTPIN (-5800 4425) SIG_NAME M_A_CPU1_SA_DQ<10>
J 0
(-5790 4435);
DISPLAY 0.659574 (-5790 4435);
PAINT MONO (-5790 4435);
DISPLAY INVISIBLE (-5790 4435);
FORCEPROP 1 LASTPIN (-5800 4425) BN 10
J 0
(-5812 4433);
DISPLAY 0.489362 (-5812 4433);
PAINT GREEN (-5812 4433);
FORCEPROP 2 LAST CDS_LIB mstr_standard
J 0
(-5750 4425);
DISPLAY 0.723404 (-5750 4425);
PAINT MONO (-5750 4425);
DISPLAY INVISIBLE (-5750 4425);
FORCEPROP 1 LAST BODY_TYPE PLUMBING
J 0
(-5750 4475);
DISPLAY 0.872340 (-5750 4475);
PAINT GREEN (-5750 4475);
DISPLAY INVISIBLE (-5750 4475);
FORCEPROP 1 LAST HDL_TAP TRUE
J 0
(-5425 4300);
DISPLAY 0.872340 (-5425 4300);
DISPLAY INVISIBLE (-5425 4300);
FORCEPROP 1 LAST PATH I106
J 0
(-5752 4425);
DISPLAY 0.872340 (-5752 4425);
PAINT GREEN (-5752 4425);
DISPLAY INVISIBLE (-5752 4425);
FORCEADD TAP..1
(-5750 4575);
FORCEPROP 3 LASTPIN (-5800 4575) SIG_NAME M_A_CPU1_SA_DQ<13>
J 0
(-5790 4585);
DISPLAY 0.659574 (-5790 4585);
PAINT MONO (-5790 4585);
DISPLAY INVISIBLE (-5790 4585);
FORCEPROP 1 LASTPIN (-5800 4575) BN 13
J 0
(-5812 4583);
DISPLAY 0.489362 (-5812 4583);
PAINT GREEN (-5812 4583);
FORCEPROP 2 LAST CDS_LIB mstr_standard
J 0
(-5750 4575);
DISPLAY 0.723404 (-5750 4575);
PAINT MONO (-5750 4575);
DISPLAY INVISIBLE (-5750 4575);
FORCEPROP 1 LAST BODY_TYPE PLUMBING
J 0
(-5750 4625);
DISPLAY 0.872340 (-5750 4625);
PAINT GREEN (-5750 4625);
DISPLAY INVISIBLE (-5750 4625);
FORCEPROP 1 LAST HDL_TAP TRUE
J 0
(-5425 4450);
DISPLAY 0.872340 (-5425 4450);
DISPLAY INVISIBLE (-5425 4450);
FORCEPROP 1 LAST PATH I107
J 0
(-5752 4575);
DISPLAY 0.872340 (-5752 4575);
PAINT GREEN (-5752 4575);
DISPLAY INVISIBLE (-5752 4575);
FORCEADD TAP..1
(-5750 4625);
FORCEPROP 3 LASTPIN (-5800 4625) SIG_NAME M_A_CPU1_SA_DQ<14>
J 0
(-5790 4635);
DISPLAY 0.659574 (-5790 4635);
PAINT MONO (-5790 4635);
DISPLAY INVISIBLE (-5790 4635);
FORCEPROP 1 LASTPIN (-5800 4625) BN 14
J 0
(-5812 4633);
DISPLAY 0.489362 (-5812 4633);
PAINT GREEN (-5812 4633);
FORCEPROP 2 LAST CDS_LIB mstr_standard
J 0
(-5750 4625);
DISPLAY 0.723404 (-5750 4625);
PAINT MONO (-5750 4625);
DISPLAY INVISIBLE (-5750 4625);
FORCEPROP 1 LAST BODY_TYPE PLUMBING
J 0
(-5750 4675);
DISPLAY 0.872340 (-5750 4675);
PAINT GREEN (-5750 4675);
DISPLAY INVISIBLE (-5750 4675);
FORCEPROP 1 LAST HDL_TAP TRUE
J 0
(-5425 4500);
DISPLAY 0.872340 (-5425 4500);
DISPLAY INVISIBLE (-5425 4500);
FORCEPROP 1 LAST PATH I108
J 0
(-5752 4625);
DISPLAY 0.872340 (-5752 4625);
PAINT GREEN (-5752 4625);
DISPLAY INVISIBLE (-5752 4625);
FORCEADD TAP..1
(-5750 4775);
FORCEPROP 3 LASTPIN (-5800 4775) SIG_NAME M_A_CPU1_SA_DQ<17>
J 0
(-5790 4785);
DISPLAY 0.659574 (-5790 4785);
PAINT MONO (-5790 4785);
DISPLAY INVISIBLE (-5790 4785);
FORCEPROP 1 LASTPIN (-5800 4775) BN 17
J 0
(-5812 4783);
DISPLAY 0.489362 (-5812 4783);
PAINT GREEN (-5812 4783);
FORCEPROP 2 LAST CDS_LIB mstr_standard
J 0
(-5750 4775);
DISPLAY 0.723404 (-5750 4775);
PAINT MONO (-5750 4775);
DISPLAY INVISIBLE (-5750 4775);
FORCEPROP 1 LAST BODY_TYPE PLUMBING
J 0
(-5750 4825);
DISPLAY 0.872340 (-5750 4825);
PAINT GREEN (-5750 4825);
DISPLAY INVISIBLE (-5750 4825);
FORCEPROP 1 LAST HDL_TAP TRUE
J 0
(-5425 4650);
DISPLAY 0.872340 (-5425 4650);
DISPLAY INVISIBLE (-5425 4650);
FORCEPROP 1 LAST PATH I109
J 0
(-5752 4775);
DISPLAY 0.872340 (-5752 4775);
PAINT GREEN (-5752 4775);
DISPLAY INVISIBLE (-5752 4775);
FORCEADD OFFPAGE..6
(-8050 4125);
FORCEPROP 2 LAST $XR0 37 
J 0
(-8329 4125);
DISPLAY 0.638298 (-8329 4125);
PAINT MONO (-8329 4125);
FORCEPROP 2 LAST CDS_LIB mstr_standard
J 0
(-8050 4125);
DISPLAY 0.723404 (-8050 4125);
PAINT MONO (-8050 4125);
DISPLAY INVISIBLE (-8050 4125);
FORCEPROP 1 LAST OFFPAGE TRUE
J 0
(-7725 4000);
DISPLAY 0.872340 (-7725 4000);
PAINT GREEN (-7725 4000);
DISPLAY INVISIBLE (-7725 4000);
FORCEPROP 1 LAST COMMENT_BODY TRUE
J 0
(-7950 4050);
DISPLAY 0.872340 (-7950 4050);
PAINT GREEN (-7950 4050);
DISPLAY INVISIBLE (-7950 4050);
FORCEPROP 2 LAST PATH I11
J 0
(-8325 4175);
DISPLAY 1.021277 (-8325 4175);
DISPLAY INVISIBLE (-8325 4175);
FORCEADD TAP..1
(-5750 4725);
FORCEPROP 3 LASTPIN (-5800 4725) SIG_NAME M_A_CPU1_SA_DQ<16>
J 0
(-5790 4735);
DISPLAY 0.659574 (-5790 4735);
PAINT MONO (-5790 4735);
DISPLAY INVISIBLE (-5790 4735);
FORCEPROP 1 LASTPIN (-5800 4725) BN 16
J 0
(-5812 4733);
DISPLAY 0.489362 (-5812 4733);
PAINT GREEN (-5812 4733);
FORCEPROP 2 LAST CDS_LIB mstr_standard
J 0
(-5750 4725);
DISPLAY 0.723404 (-5750 4725);
PAINT MONO (-5750 4725);
DISPLAY INVISIBLE (-5750 4725);
FORCEPROP 1 LAST BODY_TYPE PLUMBING
J 0
(-5750 4775);
DISPLAY 0.872340 (-5750 4775);
PAINT GREEN (-5750 4775);
DISPLAY INVISIBLE (-5750 4775);
FORCEPROP 1 LAST HDL_TAP TRUE
J 0
(-5425 4600);
DISPLAY 0.872340 (-5425 4600);
DISPLAY INVISIBLE (-5425 4600);
FORCEPROP 1 LAST PATH I110
J 0
(-5752 4725);
DISPLAY 0.872340 (-5752 4725);
PAINT GREEN (-5752 4725);
DISPLAY INVISIBLE (-5752 4725);
FORCEADD TAP..1
(-5750 4675);
FORCEPROP 3 LASTPIN (-5800 4675) SIG_NAME M_A_CPU1_SA_DQ<15>
J 0
(-5790 4685);
DISPLAY 0.659574 (-5790 4685);
PAINT MONO (-5790 4685);
DISPLAY INVISIBLE (-5790 4685);
FORCEPROP 1 LASTPIN (-5800 4675) BN 15
J 0
(-5812 4683);
DISPLAY 0.489362 (-5812 4683);
PAINT GREEN (-5812 4683);
FORCEPROP 2 LAST CDS_LIB mstr_standard
J 0
(-5750 4675);
DISPLAY 0.723404 (-5750 4675);
PAINT MONO (-5750 4675);
DISPLAY INVISIBLE (-5750 4675);
FORCEPROP 1 LAST BODY_TYPE PLUMBING
J 0
(-5750 4725);
DISPLAY 0.872340 (-5750 4725);
PAINT GREEN (-5750 4725);
DISPLAY INVISIBLE (-5750 4725);
FORCEPROP 1 LAST HDL_TAP TRUE
J 0
(-5425 4550);
DISPLAY 0.872340 (-5425 4550);
DISPLAY INVISIBLE (-5425 4550);
FORCEPROP 1 LAST PATH I111
J 0
(-5752 4675);
DISPLAY 0.872340 (-5752 4675);
PAINT GREEN (-5752 4675);
DISPLAY INVISIBLE (-5752 4675);
FORCEADD TAP..1
(-5750 4825);
FORCEPROP 3 LASTPIN (-5800 4825) SIG_NAME M_A_CPU1_SA_DQ<18>
J 0
(-5790 4835);
DISPLAY 0.659574 (-5790 4835);
PAINT MONO (-5790 4835);
DISPLAY INVISIBLE (-5790 4835);
FORCEPROP 1 LASTPIN (-5800 4825) BN 18
J 0
(-5812 4833);
DISPLAY 0.489362 (-5812 4833);
PAINT GREEN (-5812 4833);
FORCEPROP 2 LAST CDS_LIB mstr_standard
J 0
(-5750 4825);
DISPLAY 0.723404 (-5750 4825);
PAINT MONO (-5750 4825);
DISPLAY INVISIBLE (-5750 4825);
FORCEPROP 1 LAST BODY_TYPE PLUMBING
J 0
(-5750 4875);
DISPLAY 0.872340 (-5750 4875);
PAINT GREEN (-5750 4875);
DISPLAY INVISIBLE (-5750 4875);
FORCEPROP 1 LAST HDL_TAP TRUE
J 0
(-5425 4700);
DISPLAY 0.872340 (-5425 4700);
DISPLAY INVISIBLE (-5425 4700);
FORCEPROP 1 LAST PATH I112
J 0
(-5752 4825);
DISPLAY 0.872340 (-5752 4825);
PAINT GREEN (-5752 4825);
DISPLAY INVISIBLE (-5752 4825);
FORCEADD TAP..1
(-5750 4875);
FORCEPROP 3 LASTPIN (-5800 4875) SIG_NAME M_A_CPU1_SA_DQ<19>
J 0
(-5790 4885);
DISPLAY 0.659574 (-5790 4885);
PAINT MONO (-5790 4885);
DISPLAY INVISIBLE (-5790 4885);
FORCEPROP 1 LASTPIN (-5800 4875) BN 19
J 0
(-5812 4883);
DISPLAY 0.489362 (-5812 4883);
PAINT GREEN (-5812 4883);
FORCEPROP 2 LAST CDS_LIB mstr_standard
J 0
(-5750 4875);
DISPLAY 0.723404 (-5750 4875);
PAINT MONO (-5750 4875);
DISPLAY INVISIBLE (-5750 4875);
FORCEPROP 1 LAST BODY_TYPE PLUMBING
J 0
(-5750 4925);
DISPLAY 0.872340 (-5750 4925);
PAINT GREEN (-5750 4925);
DISPLAY INVISIBLE (-5750 4925);
FORCEPROP 1 LAST HDL_TAP TRUE
J 0
(-5425 4750);
DISPLAY 0.872340 (-5425 4750);
DISPLAY INVISIBLE (-5425 4750);
FORCEPROP 1 LAST PATH I113
J 0
(-5752 4875);
DISPLAY 0.872340 (-5752 4875);
PAINT GREEN (-5752 4875);
DISPLAY INVISIBLE (-5752 4875);
FORCEADD TAP..1
(-5750 5025);
FORCEPROP 3 LASTPIN (-5800 5025) SIG_NAME M_A_CPU1_SA_DQ<22>
J 0
(-5790 5035);
DISPLAY 0.659574 (-5790 5035);
PAINT MONO (-5790 5035);
DISPLAY INVISIBLE (-5790 5035);
FORCEPROP 1 LASTPIN (-5800 5025) BN 22
J 0
(-5812 5033);
DISPLAY 0.489362 (-5812 5033);
PAINT GREEN (-5812 5033);
FORCEPROP 2 LAST CDS_LIB mstr_standard
J 0
(-5750 5025);
DISPLAY 0.723404 (-5750 5025);
PAINT MONO (-5750 5025);
DISPLAY INVISIBLE (-5750 5025);
FORCEPROP 1 LAST BODY_TYPE PLUMBING
J 0
(-5750 5075);
DISPLAY 0.872340 (-5750 5075);
PAINT GREEN (-5750 5075);
DISPLAY INVISIBLE (-5750 5075);
FORCEPROP 1 LAST HDL_TAP TRUE
J 0
(-5425 4900);
DISPLAY 0.872340 (-5425 4900);
DISPLAY INVISIBLE (-5425 4900);
FORCEPROP 1 LAST PATH I114
J 0
(-5752 5025);
DISPLAY 0.872340 (-5752 5025);
PAINT GREEN (-5752 5025);
DISPLAY INVISIBLE (-5752 5025);
FORCEADD TAP..1
(-5750 4975);
FORCEPROP 3 LASTPIN (-5800 4975) SIG_NAME M_A_CPU1_SA_DQ<21>
J 0
(-5790 4985);
DISPLAY 0.659574 (-5790 4985);
PAINT MONO (-5790 4985);
DISPLAY INVISIBLE (-5790 4985);
FORCEPROP 1 LASTPIN (-5800 4975) BN 21
J 0
(-5812 4983);
DISPLAY 0.489362 (-5812 4983);
PAINT GREEN (-5812 4983);
FORCEPROP 2 LAST CDS_LIB mstr_standard
J 0
(-5750 4975);
DISPLAY 0.723404 (-5750 4975);
PAINT MONO (-5750 4975);
DISPLAY INVISIBLE (-5750 4975);
FORCEPROP 1 LAST BODY_TYPE PLUMBING
J 0
(-5750 5025);
DISPLAY 0.872340 (-5750 5025);
PAINT GREEN (-5750 5025);
DISPLAY INVISIBLE (-5750 5025);
FORCEPROP 1 LAST HDL_TAP TRUE
J 0
(-5425 4850);
DISPLAY 0.872340 (-5425 4850);
DISPLAY INVISIBLE (-5425 4850);
FORCEPROP 1 LAST PATH I115
J 0
(-5752 4975);
DISPLAY 0.872340 (-5752 4975);
PAINT GREEN (-5752 4975);
DISPLAY INVISIBLE (-5752 4975);
FORCEADD TAP..1
(-5750 4925);
FORCEPROP 3 LASTPIN (-5800 4925) SIG_NAME M_A_CPU1_SA_DQ<20>
J 0
(-5790 4935);
DISPLAY 0.659574 (-5790 4935);
PAINT MONO (-5790 4935);
DISPLAY INVISIBLE (-5790 4935);
FORCEPROP 1 LASTPIN (-5800 4925) BN 20
J 0
(-5812 4933);
DISPLAY 0.489362 (-5812 4933);
PAINT GREEN (-5812 4933);
FORCEPROP 2 LAST CDS_LIB mstr_standard
J 0
(-5750 4925);
DISPLAY 0.723404 (-5750 4925);
PAINT MONO (-5750 4925);
DISPLAY INVISIBLE (-5750 4925);
FORCEPROP 1 LAST BODY_TYPE PLUMBING
J 0
(-5750 4975);
DISPLAY 0.872340 (-5750 4975);
PAINT GREEN (-5750 4975);
DISPLAY INVISIBLE (-5750 4975);
FORCEPROP 1 LAST HDL_TAP TRUE
J 0
(-5425 4800);
DISPLAY 0.872340 (-5425 4800);
DISPLAY INVISIBLE (-5425 4800);
FORCEPROP 1 LAST PATH I116
J 0
(-5752 4925);
DISPLAY 0.872340 (-5752 4925);
PAINT GREEN (-5752 4925);
DISPLAY INVISIBLE (-5752 4925);
FORCEADD TAP..1
(-5750 5125);
FORCEPROP 3 LASTPIN (-5800 5125) SIG_NAME M_A_CPU1_SA_DQ<24>
J 0
(-5790 5135);
DISPLAY 0.659574 (-5790 5135);
PAINT MONO (-5790 5135);
DISPLAY INVISIBLE (-5790 5135);
FORCEPROP 1 LASTPIN (-5800 5125) BN 24
J 0
(-5812 5133);
DISPLAY 0.489362 (-5812 5133);
PAINT GREEN (-5812 5133);
FORCEPROP 2 LAST CDS_LIB mstr_standard
J 0
(-5750 5125);
DISPLAY 0.723404 (-5750 5125);
PAINT MONO (-5750 5125);
DISPLAY INVISIBLE (-5750 5125);
FORCEPROP 1 LAST BODY_TYPE PLUMBING
J 0
(-5750 5175);
DISPLAY 0.872340 (-5750 5175);
PAINT GREEN (-5750 5175);
DISPLAY INVISIBLE (-5750 5175);
FORCEPROP 1 LAST HDL_TAP TRUE
J 0
(-5425 5000);
DISPLAY 0.872340 (-5425 5000);
DISPLAY INVISIBLE (-5425 5000);
FORCEPROP 1 LAST PATH I117
J 0
(-5752 5125);
DISPLAY 0.872340 (-5752 5125);
PAINT GREEN (-5752 5125);
DISPLAY INVISIBLE (-5752 5125);
FORCEADD TAP..1
(-5750 5075);
FORCEPROP 3 LASTPIN (-5800 5075) SIG_NAME M_A_CPU1_SA_DQ<23>
J 0
(-5790 5085);
DISPLAY 0.659574 (-5790 5085);
PAINT MONO (-5790 5085);
DISPLAY INVISIBLE (-5790 5085);
FORCEPROP 1 LASTPIN (-5800 5075) BN 23
J 0
(-5812 5083);
DISPLAY 0.489362 (-5812 5083);
PAINT GREEN (-5812 5083);
FORCEPROP 2 LAST CDS_LIB mstr_standard
J 0
(-5750 5075);
DISPLAY 0.723404 (-5750 5075);
PAINT MONO (-5750 5075);
DISPLAY INVISIBLE (-5750 5075);
FORCEPROP 1 LAST BODY_TYPE PLUMBING
J 0
(-5750 5125);
DISPLAY 0.872340 (-5750 5125);
PAINT GREEN (-5750 5125);
DISPLAY INVISIBLE (-5750 5125);
FORCEPROP 1 LAST HDL_TAP TRUE
J 0
(-5425 4950);
DISPLAY 0.872340 (-5425 4950);
DISPLAY INVISIBLE (-5425 4950);
FORCEPROP 1 LAST PATH I118
J 0
(-5752 5075);
DISPLAY 0.872340 (-5752 5075);
PAINT GREEN (-5752 5075);
DISPLAY INVISIBLE (-5752 5075);
FORCEADD TAP..1
(-5750 5225);
FORCEPROP 3 LASTPIN (-5800 5225) SIG_NAME M_A_CPU1_SA_DQ<26>
J 0
(-5790 5235);
DISPLAY 0.659574 (-5790 5235);
PAINT MONO (-5790 5235);
DISPLAY INVISIBLE (-5790 5235);
FORCEPROP 1 LASTPIN (-5800 5225) BN 26
J 0
(-5812 5233);
DISPLAY 0.489362 (-5812 5233);
PAINT GREEN (-5812 5233);
FORCEPROP 2 LAST CDS_LIB mstr_standard
J 0
(-5750 5225);
DISPLAY 0.723404 (-5750 5225);
PAINT MONO (-5750 5225);
DISPLAY INVISIBLE (-5750 5225);
FORCEPROP 1 LAST BODY_TYPE PLUMBING
J 0
(-5750 5275);
DISPLAY 0.872340 (-5750 5275);
PAINT GREEN (-5750 5275);
DISPLAY INVISIBLE (-5750 5275);
FORCEPROP 1 LAST HDL_TAP TRUE
J 0
(-5425 5100);
DISPLAY 0.872340 (-5425 5100);
DISPLAY INVISIBLE (-5425 5100);
FORCEPROP 1 LAST PATH I119
J 0
(-5752 5225);
DISPLAY 0.872340 (-5752 5225);
PAINT GREEN (-5752 5225);
DISPLAY INVISIBLE (-5752 5225);
FORCEADD OFFPAGE..1
(-8050 4175);
FORCEPROP 2 LAST $XR0 37 
J 0
(-8271 4175);
DISPLAY 0.638298 (-8271 4175);
PAINT MONO (-8271 4175);
FORCEPROP 2 LAST CDS_LIB mstr_standard
J 0
(-8050 4175);
DISPLAY 0.808511 (-8050 4175);
DISPLAY INVISIBLE (-8050 4175);
FORCEPROP 1 LAST OFFPAGE TRUE
J 0
(-7725 4050);
DISPLAY 0.872340 (-7725 4050);
PAINT GREEN (-7725 4050);
DISPLAY INVISIBLE (-7725 4050);
FORCEPROP 1 LAST COMMENT_BODY TRUE
J 0
(-7925 4075);
DISPLAY 0.872340 (-7925 4075);
PAINT GREEN (-7925 4075);
DISPLAY INVISIBLE (-7925 4075);
FORCEPROP 2 LAST PATH I12
J 0
(-8300 4225);
DISPLAY 1.021277 (-8300 4225);
DISPLAY INVISIBLE (-8300 4225);
FORCEADD TAP..1
(-5750 5275);
FORCEPROP 3 LASTPIN (-5800 5275) SIG_NAME M_A_CPU1_SA_DQ<27>
J 0
(-5790 5285);
DISPLAY 0.659574 (-5790 5285);
PAINT MONO (-5790 5285);
DISPLAY INVISIBLE (-5790 5285);
FORCEPROP 1 LASTPIN (-5800 5275) BN 27
J 0
(-5812 5283);
DISPLAY 0.489362 (-5812 5283);
PAINT GREEN (-5812 5283);
FORCEPROP 2 LAST CDS_LIB mstr_standard
J 0
(-5750 5275);
DISPLAY 0.723404 (-5750 5275);
PAINT MONO (-5750 5275);
DISPLAY INVISIBLE (-5750 5275);
FORCEPROP 1 LAST BODY_TYPE PLUMBING
J 0
(-5750 5325);
DISPLAY 0.872340 (-5750 5325);
PAINT GREEN (-5750 5325);
DISPLAY INVISIBLE (-5750 5325);
FORCEPROP 1 LAST HDL_TAP TRUE
J 0
(-5425 5150);
DISPLAY 0.872340 (-5425 5150);
DISPLAY INVISIBLE (-5425 5150);
FORCEPROP 1 LAST PATH I120
J 0
(-5752 5275);
DISPLAY 0.872340 (-5752 5275);
PAINT GREEN (-5752 5275);
DISPLAY INVISIBLE (-5752 5275);
FORCEADD TAP..1
(-5750 5175);
FORCEPROP 3 LASTPIN (-5800 5175) SIG_NAME M_A_CPU1_SA_DQ<25>
J 0
(-5790 5185);
DISPLAY 0.659574 (-5790 5185);
PAINT MONO (-5790 5185);
DISPLAY INVISIBLE (-5790 5185);
FORCEPROP 1 LASTPIN (-5800 5175) BN 25
J 0
(-5812 5183);
DISPLAY 0.489362 (-5812 5183);
PAINT GREEN (-5812 5183);
FORCEPROP 2 LAST CDS_LIB mstr_standard
J 0
(-5750 5175);
DISPLAY 0.723404 (-5750 5175);
PAINT MONO (-5750 5175);
DISPLAY INVISIBLE (-5750 5175);
FORCEPROP 1 LAST BODY_TYPE PLUMBING
J 0
(-5750 5225);
DISPLAY 0.872340 (-5750 5225);
PAINT GREEN (-5750 5225);
DISPLAY INVISIBLE (-5750 5225);
FORCEPROP 1 LAST HDL_TAP TRUE
J 0
(-5425 5050);
DISPLAY 0.872340 (-5425 5050);
DISPLAY INVISIBLE (-5425 5050);
FORCEPROP 1 LAST PATH I121
J 0
(-5752 5175);
DISPLAY 0.872340 (-5752 5175);
PAINT GREEN (-5752 5175);
DISPLAY INVISIBLE (-5752 5175);
FORCEADD TAP..1
(-5750 5425);
FORCEPROP 3 LASTPIN (-5800 5425) SIG_NAME M_A_CPU1_SA_DQ<30>
J 0
(-5790 5435);
DISPLAY 0.659574 (-5790 5435);
PAINT MONO (-5790 5435);
DISPLAY INVISIBLE (-5790 5435);
FORCEPROP 1 LASTPIN (-5800 5425) BN 30
J 0
(-5812 5433);
DISPLAY 0.489362 (-5812 5433);
PAINT GREEN (-5812 5433);
FORCEPROP 2 LAST CDS_LIB mstr_standard
J 0
(-5750 5425);
DISPLAY 0.723404 (-5750 5425);
PAINT MONO (-5750 5425);
DISPLAY INVISIBLE (-5750 5425);
FORCEPROP 1 LAST BODY_TYPE PLUMBING
J 0
(-5750 5475);
DISPLAY 0.872340 (-5750 5475);
PAINT GREEN (-5750 5475);
DISPLAY INVISIBLE (-5750 5475);
FORCEPROP 1 LAST HDL_TAP TRUE
J 0
(-5425 5300);
DISPLAY 0.872340 (-5425 5300);
DISPLAY INVISIBLE (-5425 5300);
FORCEPROP 1 LAST PATH I122
J 0
(-5752 5425);
DISPLAY 0.872340 (-5752 5425);
PAINT GREEN (-5752 5425);
DISPLAY INVISIBLE (-5752 5425);
FORCEADD TAP..1
(-5750 5325);
FORCEPROP 3 LASTPIN (-5800 5325) SIG_NAME M_A_CPU1_SA_DQ<28>
J 0
(-5790 5335);
DISPLAY 0.659574 (-5790 5335);
PAINT MONO (-5790 5335);
DISPLAY INVISIBLE (-5790 5335);
FORCEPROP 1 LASTPIN (-5800 5325) BN 28
J 0
(-5812 5333);
DISPLAY 0.489362 (-5812 5333);
PAINT GREEN (-5812 5333);
FORCEPROP 2 LAST CDS_LIB mstr_standard
J 0
(-5750 5325);
DISPLAY 0.723404 (-5750 5325);
PAINT MONO (-5750 5325);
DISPLAY INVISIBLE (-5750 5325);
FORCEPROP 1 LAST BODY_TYPE PLUMBING
J 0
(-5750 5375);
DISPLAY 0.872340 (-5750 5375);
PAINT GREEN (-5750 5375);
DISPLAY INVISIBLE (-5750 5375);
FORCEPROP 1 LAST HDL_TAP TRUE
J 0
(-5425 5200);
DISPLAY 0.872340 (-5425 5200);
DISPLAY INVISIBLE (-5425 5200);
FORCEPROP 1 LAST PATH I123
J 0
(-5752 5325);
DISPLAY 0.872340 (-5752 5325);
PAINT GREEN (-5752 5325);
DISPLAY INVISIBLE (-5752 5325);
FORCEADD TAP..1
(-5750 5375);
FORCEPROP 3 LASTPIN (-5800 5375) SIG_NAME M_A_CPU1_SA_DQ<29>
J 0
(-5790 5385);
DISPLAY 0.659574 (-5790 5385);
PAINT MONO (-5790 5385);
DISPLAY INVISIBLE (-5790 5385);
FORCEPROP 1 LASTPIN (-5800 5375) BN 29
J 0
(-5812 5383);
DISPLAY 0.489362 (-5812 5383);
PAINT GREEN (-5812 5383);
FORCEPROP 2 LAST CDS_LIB mstr_standard
J 0
(-5750 5375);
DISPLAY 0.723404 (-5750 5375);
PAINT MONO (-5750 5375);
DISPLAY INVISIBLE (-5750 5375);
FORCEPROP 1 LAST BODY_TYPE PLUMBING
J 0
(-5750 5425);
DISPLAY 0.872340 (-5750 5425);
PAINT GREEN (-5750 5425);
DISPLAY INVISIBLE (-5750 5425);
FORCEPROP 1 LAST HDL_TAP TRUE
J 0
(-5425 5250);
DISPLAY 0.872340 (-5425 5250);
DISPLAY INVISIBLE (-5425 5250);
FORCEPROP 1 LAST PATH I124
J 0
(-5752 5375);
DISPLAY 0.872340 (-5752 5375);
PAINT GREEN (-5752 5375);
DISPLAY INVISIBLE (-5752 5375);
FORCEADD TAP..1
(-5750 5475);
FORCEPROP 3 LASTPIN (-5800 5475) SIG_NAME M_A_CPU1_SA_DQ<31>
J 0
(-5790 5485);
DISPLAY 0.659574 (-5790 5485);
PAINT MONO (-5790 5485);
DISPLAY INVISIBLE (-5790 5485);
FORCEPROP 1 LASTPIN (-5800 5475) BN 31
J 0
(-5812 5483);
DISPLAY 0.489362 (-5812 5483);
PAINT GREEN (-5812 5483);
FORCEPROP 2 LAST CDS_LIB mstr_standard
J 0
(-5750 5475);
DISPLAY 0.723404 (-5750 5475);
PAINT MONO (-5750 5475);
DISPLAY INVISIBLE (-5750 5475);
FORCEPROP 1 LAST BODY_TYPE PLUMBING
J 0
(-5750 5525);
DISPLAY 0.872340 (-5750 5525);
PAINT GREEN (-5750 5525);
DISPLAY INVISIBLE (-5750 5525);
FORCEPROP 1 LAST HDL_TAP TRUE
J 0
(-5425 5350);
DISPLAY 0.872340 (-5425 5350);
DISPLAY INVISIBLE (-5425 5350);
FORCEPROP 1 LAST PATH I125
J 0
(-5752 5475);
DISPLAY 0.872340 (-5752 5475);
PAINT GREEN (-5752 5475);
DISPLAY INVISIBLE (-5752 5475);
FORCEADD OFFPAGE..3
(-5150 5525);
FORCEPROP 2 LAST $XR0 37 
J 0
(-4936 5525);
DISPLAY 0.638298 (-4936 5525);
PAINT MONO (-4936 5525);
FORCEPROP 2 LAST CDS_LIB mstr_standard
J 0
(-5150 5525);
DISPLAY 0.723404 (-5150 5525);
PAINT MONO (-5150 5525);
DISPLAY INVISIBLE (-5150 5525);
FORCEPROP 1 LAST OFFPAGE TRUE
J 0
(-4825 5400);
DISPLAY 0.872340 (-4825 5400);
PAINT GREEN (-4825 5400);
DISPLAY INVISIBLE (-4825 5400);
FORCEPROP 1 LAST COMMENT_BODY TRUE
J 0
(-5200 5425);
DISPLAY 0.872340 (-5200 5425);
PAINT GREEN (-5200 5425);
DISPLAY INVISIBLE (-5200 5425);
FORCEPROP 2 LAST PATH I126
J 0
(-4825 5575);
DISPLAY 1.021277 (-4825 5575);
DISPLAY INVISIBLE (-4825 5575);
FORCEADD OFFPAGE..5
(-6900 1475);
FORCEPROP 2 LAST $XR0 98 
J 0
(-7124 1475);
DISPLAY 0.638298 (-7124 1475);
PAINT MONO (-7124 1475);
FORCEPROP 2 LAST BOM_COST MEM
J 0
(-6975 1550);
DISPLAY 0.808511 (-6975 1550);
DISPLAY INVISIBLE (-6975 1550);
FORCEPROP 2 LAST CDS_LIB mstr_standard
J 0
(-6900 1475);
DISPLAY 0.808511 (-6900 1475);
DISPLAY INVISIBLE (-6900 1475);
FORCEPROP 1 LAST OFFPAGE TRUE
J 0
(-6575 1350);
DISPLAY 0.872340 (-6575 1350);
PAINT GREEN (-6575 1350);
DISPLAY INVISIBLE (-6575 1350);
FORCEPROP 1 LAST COMMENT_BODY TRUE
J 0
(-6800 1400);
DISPLAY 0.872340 (-6800 1400);
PAINT GREEN (-6800 1400);
DISPLAY INVISIBLE (-6800 1400);
FORCEPROP 2 LAST PATH I127
J 0
(-7100 1525);
DISPLAY 1.021277 (-7100 1525);
DISPLAY INVISIBLE (-7100 1525);
FORCEADD GND..1
(-6125 1075);
FORCEPROP 3 LASTPIN (-6125 1125) SIG_NAME GND\g
J 0
(-6115 1135);
DISPLAY 0.659574 (-6115 1135);
PAINT MONO (-6115 1135);
DISPLAY INVISIBLE (-6115 1135);
FORCEPROP 2 LAST BOM_COST MEM
J 0
(-6225 1150);
DISPLAY 0.808511 (-6225 1150);
DISPLAY INVISIBLE (-6225 1150);
FORCEPROP 2 LAST CDS_LIB mstr_symbols
J 0
(-6125 1075);
DISPLAY 0.808511 (-6125 1075);
DISPLAY INVISIBLE (-6125 1075);
FORCEPROP 1 LAST SIZE 1B
J 0
(-6050 1025);
DISPLAY 0.851064 (-6050 1025);
PAINT GREEN (-6050 1025);
DISPLAY INVISIBLE (-6050 1025);
FORCEPROP 1 LAST VOLTAGE 0.0
J 0
(-6170 1032);
DISPLAY 0.723404 (-6170 1032);
PAINT SKYBLUE (-6170 1032);
DISPLAY INVISIBLE (-6170 1032);
FORCEPROP 1 LAST BODY_TYPE PLUMBING
J 0
(-6170 1032);
DISPLAY 0.340426 (-6170 1032);
PAINT GREEN (-6170 1032);
DISPLAY INVISIBLE (-6170 1032);
FORCEPROP 1 LAST HDL_POWER GND
J 0
(-6125 1225);
DISPLAY 0.851064 (-6125 1225);
PAINT GREEN (-6125 1225);
DISPLAY INVISIBLE (-6125 1225);
FORCEPROP 1 LAST PATH I128
J 0
(-6050 1075);
DISPLAY 0.872340 (-6050 1075);
PAINT AQUA (-6050 1075);
DISPLAY INVISIBLE (-6050 1075);
FORCEADD Q_RES..2
(-6125 1300);
FORCEPROP 1 LAST LOCATION R36
J 0
(-6080 1425);
DISPLAY 0.489362 (-6080 1425);
PAINT SKYBLUE (-6080 1425);
FORCEPROP 2 LAST SEC 1
J 0
(-6075 1525);
DISPLAY 0.808511 (-6075 1525);
PAINT MONO (-6075 1525);
DISPLAY INVISIBLE (-6075 1525);
FORCEPROP 1 LASTPIN (-6125 1400) $PN 1
J 0
(-6120 1362);
DISPLAY 0.489362 (-6120 1362);
PAINT WHITE (-6120 1362);
FORCEPROP 1 LASTPIN (-6125 1200) $PN 2
J 0
(-6120 1210);
DISPLAY 0.489362 (-6120 1210);
PAINT WHITE (-6120 1210);
FORCEPROP 0 LASTPIN (-6125 1400) XNET_PINS 3
R 1
J 0
(-6135 1410);
DISPLAY 0.808511 (-6135 1410);
PAINT MONO (-6135 1410);
DISPLAY INVISIBLE (-6135 1410);
FORCEPROP 0 LASTPIN (-6125 1200) XNET_PINS 2
R 1
J 2
(-6135 1190);
DISPLAY 0.808511 (-6135 1190);
PAINT MONO (-6135 1190);
DISPLAY INVISIBLE (-6135 1190);
FORCEPROP 1 LAST MATERIAL CHIP
J 0
(-6085 1225);
DISPLAY 0.489362 (-6085 1225);
PAINT SKYBLUE (-6085 1225);
FORCEPROP 1 LAST TOLERANCE 1%
J 0
(-6080 1325);
DISPLAY 0.489362 (-6080 1325);
PAINT SKYBLUE (-6080 1325);
FORCEPROP 1 LAST VALUE 10K
J 0
(-6080 1375);
DISPLAY 0.489362 (-6080 1375);
PAINT SKYBLUE (-6080 1375);
FORCEPROP 1 LAST PACK_TYPE 0402LF
J 0
(-6085 1125);
DISPLAY 0.489362 (-6085 1125);
PAINT SKYBLUE (-6085 1125);
FORCEPROP 1 LAST WATTAGE 1/16W
J 0
(-6085 1275);
DISPLAY 0.489362 (-6085 1275);
PAINT SKYBLUE (-6085 1275);
FORCEPROP 2 LAST SEC_TYPE 0402LF
J 0
(-6075 1525);
DISPLAY 0.808511 (-6075 1525);
PAINT MONO (-6075 1525);
DISPLAY INVISIBLE (-6075 1525);
FORCEPROP 2 LAST CDS_LIB pure_quanta
J 0
(-6125 1300);
DISPLAY INVISIBLE (-6125 1300);
FORCEPROP 2 LAST BOM_COST MEM
J 0
(-6075 1475);
DISPLAY 0.808511 (-6075 1475);
DISPLAY INVISIBLE (-6075 1475);
FORCEPROP 1 LAST PATH I129
J 0
(-6075 1475);
DISPLAY 0.978723 (-6075 1475);
PAINT WHITE (-6075 1475);
DISPLAY INVISIBLE (-6075 1475);
FORCEPROP 1 LAST PART_NUMBER CS31002FB08
J 0
(-6085 1175);
DISPLAY 0.489362 (-6085 1175);
PAINT SKYBLUE (-6085 1175);
DISPLAY INVISIBLE (-6085 1175);
FORCEADD OFFPAGE..1
(-8050 4325);
FORCEPROP 2 LAST $XR0 37 
J 0
(-8271 4325);
DISPLAY 0.638298 (-8271 4325);
PAINT MONO (-8271 4325);
FORCEPROP 2 LAST CDS_LIB mstr_standard
J 0
(-8050 4325);
DISPLAY 0.808511 (-8050 4325);
DISPLAY INVISIBLE (-8050 4325);
FORCEPROP 1 LAST OFFPAGE TRUE
J 0
(-7725 4200);
DISPLAY 0.872340 (-7725 4200);
PAINT GREEN (-7725 4200);
DISPLAY INVISIBLE (-7725 4200);
FORCEPROP 1 LAST COMMENT_BODY TRUE
J 0
(-7925 4225);
DISPLAY 0.872340 (-7925 4225);
PAINT GREEN (-7925 4225);
DISPLAY INVISIBLE (-7925 4225);
FORCEPROP 2 LAST PATH I13
J 0
(-8000 4400);
DISPLAY 1.021277 (-8000 4400);
DISPLAY INVISIBLE (-8000 4400);
FORCEADD GND..1
(-2100 2075);
FORCEPROP 3 LASTPIN (-2100 2125) SIG_NAME GND\g
J 0
(-2090 2135);
DISPLAY 0.659574 (-2090 2135);
PAINT MONO (-2090 2135);
DISPLAY INVISIBLE (-2090 2135);
FORCEPROP 2 LAST CDS_LIB mstr_symbols
J 0
(-2100 2075);
DISPLAY 0.723404 (-2100 2075);
DISPLAY INVISIBLE (-2100 2075);
FORCEPROP 1 LAST SIZE 1B
J 0
(-2025 2025);
DISPLAY 0.851064 (-2025 2025);
PAINT GREEN (-2025 2025);
DISPLAY INVISIBLE (-2025 2025);
FORCEPROP 1 LAST VOLTAGE 0.0
J 0
(-2145 2032);
DISPLAY 0.723404 (-2145 2032);
PAINT SKYBLUE (-2145 2032);
DISPLAY INVISIBLE (-2145 2032);
FORCEPROP 1 LAST BODY_TYPE PLUMBING
J 0
(-2145 2032);
DISPLAY 0.340426 (-2145 2032);
PAINT GREEN (-2145 2032);
DISPLAY INVISIBLE (-2145 2032);
FORCEPROP 1 LAST HDL_POWER GND
J 0
(-2100 2225);
DISPLAY 0.851064 (-2100 2225);
PAINT GREEN (-2100 2225);
DISPLAY INVISIBLE (-2100 2225);
FORCEPROP 1 LAST PATH I130
J 0
(-2025 2075);
DISPLAY 0.872340 (-2025 2075);
PAINT AQUA (-2025 2075);
DISPLAY INVISIBLE (-2025 2075);
FORCEADD OFFPAGE..1
(-8050 4375);
FORCEPROP 2 LAST $XR0 37 
J 0
(-8271 4375);
DISPLAY 0.638298 (-8271 4375);
PAINT MONO (-8271 4375);
FORCEPROP 2 LAST CDS_LIB mstr_standard
J 0
(-8050 4375);
DISPLAY 0.723404 (-8050 4375);
PAINT MONO (-8050 4375);
DISPLAY INVISIBLE (-8050 4375);
FORCEPROP 1 LAST OFFPAGE TRUE
J 0
(-7725 4250);
DISPLAY 0.872340 (-7725 4250);
PAINT GREEN (-7725 4250);
DISPLAY INVISIBLE (-7725 4250);
FORCEPROP 1 LAST COMMENT_BODY TRUE
J 0
(-7925 4275);
DISPLAY 0.872340 (-7925 4275);
PAINT GREEN (-7925 4275);
DISPLAY INVISIBLE (-7925 4275);
FORCEPROP 2 LAST PATH I14
J 0
(-8000 4450);
DISPLAY 1.021277 (-8000 4450);
DISPLAY INVISIBLE (-8000 4450);
FORCEADD GND..1
(-500 1875);
FORCEPROP 3 LASTPIN (-500 1925) SIG_NAME GND\g
J 0
(-490 1935);
DISPLAY 0.659574 (-490 1935);
PAINT MONO (-490 1935);
DISPLAY INVISIBLE (-490 1935);
FORCEPROP 2 LAST CDS_LIB mstr_symbols
J 0
(-500 1875);
DISPLAY 0.723404 (-500 1875);
DISPLAY INVISIBLE (-500 1875);
FORCEPROP 1 LAST SIZE 1B
J 0
(-425 1825);
DISPLAY 0.851064 (-425 1825);
PAINT GREEN (-425 1825);
DISPLAY INVISIBLE (-425 1825);
FORCEPROP 1 LAST VOLTAGE 0.0
J 0
(-545 1832);
DISPLAY 0.723404 (-545 1832);
PAINT SKYBLUE (-545 1832);
DISPLAY INVISIBLE (-545 1832);
FORCEPROP 1 LAST BODY_TYPE PLUMBING
J 0
(-545 1832);
DISPLAY 0.340426 (-545 1832);
PAINT GREEN (-545 1832);
DISPLAY INVISIBLE (-545 1832);
FORCEPROP 1 LAST HDL_POWER GND
J 0
(-500 2025);
DISPLAY 0.851064 (-500 2025);
PAINT GREEN (-500 2025);
DISPLAY INVISIBLE (-500 2025);
FORCEPROP 1 LAST PATH I146
J 0
(-425 1875);
DISPLAY 0.872340 (-425 1875);
PAINT AQUA (-425 1875);
DISPLAY INVISIBLE (-425 1875);
FORCEADD OFFPAGE..1
(-8050 4225);
FORCEPROP 2 LAST $XR0 37 
J 0
(-8271 4225);
DISPLAY 0.638298 (-8271 4225);
PAINT MONO (-8271 4225);
FORCEPROP 2 LAST CDS_LIB mstr_standard
J 0
(-8050 4225);
DISPLAY 0.723404 (-8050 4225);
PAINT MONO (-8050 4225);
DISPLAY INVISIBLE (-8050 4225);
FORCEPROP 1 LAST OFFPAGE TRUE
J 0
(-7725 4100);
DISPLAY 0.872340 (-7725 4100);
PAINT GREEN (-7725 4100);
DISPLAY INVISIBLE (-7725 4100);
FORCEPROP 1 LAST COMMENT_BODY TRUE
J 0
(-7925 4125);
DISPLAY 0.872340 (-7925 4125);
PAINT GREEN (-7925 4125);
DISPLAY INVISIBLE (-7925 4125);
FORCEPROP 2 LAST PATH I15
J 0
(-8300 4275);
DISPLAY 1.021277 (-8300 4275);
DISPLAY INVISIBLE (-8300 4275);
FORCEADD OFFPAGE..1
(-8050 4625);
FORCEPROP 2 LAST $XR0 37 
J 0
(-8271 4625);
DISPLAY 0.638298 (-8271 4625);
PAINT MONO (-8271 4625);
FORCEPROP 2 LAST CDS_LIB mstr_standard
J 0
(-8050 4625);
DISPLAY 0.808511 (-8050 4625);
DISPLAY INVISIBLE (-8050 4625);
FORCEPROP 1 LAST OFFPAGE TRUE
J 0
(-7725 4500);
DISPLAY 0.872340 (-7725 4500);
PAINT GREEN (-7725 4500);
DISPLAY INVISIBLE (-7725 4500);
FORCEPROP 1 LAST COMMENT_BODY TRUE
J 0
(-7925 4525);
DISPLAY 0.872340 (-7925 4525);
PAINT GREEN (-7925 4525);
DISPLAY INVISIBLE (-7925 4525);
FORCEPROP 2 LAST PATH I16
J 0
(-8300 4675);
DISPLAY 1.021277 (-8300 4675);
DISPLAY INVISIBLE (-8300 4675);
FORCEADD OFFPAGE..1
(-8050 4475);
FORCEPROP 2 LAST $XR0 37 
J 0
(-8271 4475);
DISPLAY 0.638298 (-8271 4475);
PAINT MONO (-8271 4475);
FORCEPROP 2 LAST CDS_LIB mstr_standard
J 0
(-8050 4475);
DISPLAY 0.808511 (-8050 4475);
DISPLAY INVISIBLE (-8050 4475);
FORCEPROP 1 LAST OFFPAGE TRUE
J 0
(-7725 4350);
DISPLAY 0.872340 (-7725 4350);
PAINT GREEN (-7725 4350);
DISPLAY INVISIBLE (-7725 4350);
FORCEPROP 1 LAST COMMENT_BODY TRUE
J 0
(-7925 4375);
DISPLAY 0.872340 (-7925 4375);
PAINT GREEN (-7925 4375);
DISPLAY INVISIBLE (-7925 4375);
FORCEPROP 2 LAST PATH I17
J 0
(-8300 4525);
DISPLAY 1.021277 (-8300 4525);
DISPLAY INVISIBLE (-8300 4525);
FORCEADD SCONN288_DDR506112002KQ..3
(-1300 3825);
FORCEPROP 1 LAST LOCATION J24
J 0
(-1750 5800);
DISPLAY 0.468085 (-1750 5800);
PAINT SKYBLUE (-1750 5800);
FORCEPROP 0 LAST $SEC 3
J 0
(-1750 5950);
DISPLAY 0.680851 (-1750 5950);
PAINT MONO (-1750 5950);
DISPLAY INVISIBLE (-1750 5950);
FORCEPROP 0 LAST CDS_SEC 3
J 0
(-1750 5950);
DISPLAY 0.680851 (-1750 5950);
DISPLAY INVISIBLE (-1750 5950);
FORCEPROP 0 LASTPIN (-700 2225) $PN G1
J 0
(-690 2235);
DISPLAY 0.680851 (-690 2235);
PAINT MONO (-690 2235);
FORCEPROP 0 LASTPIN (-700 2175) $PN G2
J 0
(-690 2185);
DISPLAY 0.680851 (-690 2185);
PAINT MONO (-690 2185);
FORCEPROP 0 LASTPIN (-700 2125) $PN G3
J 0
(-690 2135);
DISPLAY 0.680851 (-690 2135);
PAINT MONO (-690 2135);
FORCEPROP 0 LASTPIN (-1900 5375) $PN 1
J 2
(-1910 5385);
DISPLAY 0.680851 (-1910 5385);
PAINT MONO (-1910 5385);
FORCEPROP 0 LASTPIN (-1900 5425) $PN 145
J 2
(-1910 5435);
DISPLAY 0.680851 (-1910 5435);
PAINT MONO (-1910 5435);
FORCEPROP 0 LASTPIN (-1900 5475) $PN 146
J 2
(-1910 5485);
DISPLAY 0.680851 (-1910 5485);
PAINT MONO (-1910 5485);
FORCEPROP 0 LASTPIN (-700 2325) $PN 6
J 0
(-690 2335);
DISPLAY 0.680851 (-690 2335);
PAINT MONO (-690 2335);
FORCEPROP 0 LASTPIN (-700 2375) $PN 8
J 0
(-690 2385);
DISPLAY 0.680851 (-690 2385);
PAINT MONO (-690 2385);
FORCEPROP 0 LASTPIN (-700 2425) $PN 10
J 0
(-690 2435);
DISPLAY 0.680851 (-690 2435);
PAINT MONO (-690 2435);
FORCEPROP 0 LASTPIN (-700 2475) $PN 13
J 0
(-690 2485);
DISPLAY 0.680851 (-690 2485);
PAINT MONO (-690 2485);
FORCEPROP 0 LASTPIN (-700 2525) $PN 15
J 0
(-690 2535);
DISPLAY 0.680851 (-690 2535);
PAINT MONO (-690 2535);
FORCEPROP 0 LASTPIN (-700 2575) $PN 17
J 0
(-690 2585);
DISPLAY 0.680851 (-690 2585);
PAINT MONO (-690 2585);
FORCEPROP 0 LASTPIN (-700 2625) $PN 19
J 0
(-690 2635);
DISPLAY 0.680851 (-690 2635);
PAINT MONO (-690 2635);
FORCEPROP 0 LASTPIN (-700 2675) $PN 21
J 0
(-690 2685);
DISPLAY 0.680851 (-690 2685);
PAINT MONO (-690 2685);
FORCEPROP 0 LASTPIN (-700 2725) $PN 24
J 0
(-690 2735);
DISPLAY 0.680851 (-690 2735);
PAINT MONO (-690 2735);
FORCEPROP 0 LASTPIN (-700 2775) $PN 26
J 0
(-690 2785);
DISPLAY 0.680851 (-690 2785);
PAINT MONO (-690 2785);
FORCEPROP 0 LASTPIN (-700 2825) $PN 28
J 0
(-690 2835);
DISPLAY 0.680851 (-690 2835);
PAINT MONO (-690 2835);
FORCEPROP 0 LASTPIN (-700 2875) $PN 30
J 0
(-690 2885);
DISPLAY 0.680851 (-690 2885);
PAINT MONO (-690 2885);
FORCEPROP 0 LASTPIN (-700 2925) $PN 32
J 0
(-690 2935);
DISPLAY 0.680851 (-690 2935);
PAINT MONO (-690 2935);
FORCEPROP 0 LASTPIN (-700 2975) $PN 35
J 0
(-690 2985);
DISPLAY 0.680851 (-690 2985);
PAINT MONO (-690 2985);
FORCEPROP 0 LASTPIN (-700 3025) $PN 37
J 0
(-690 3035);
DISPLAY 0.680851 (-690 3035);
PAINT MONO (-690 3035);
FORCEPROP 0 LASTPIN (-700 3075) $PN 39
J 0
(-690 3085);
DISPLAY 0.680851 (-690 3085);
PAINT MONO (-690 3085);
FORCEPROP 0 LASTPIN (-700 3125) $PN 41
J 0
(-690 3135);
DISPLAY 0.680851 (-690 3135);
PAINT MONO (-690 3135);
FORCEPROP 0 LASTPIN (-700 3175) $PN 43
J 0
(-690 3185);
DISPLAY 0.680851 (-690 3185);
PAINT MONO (-690 3185);
FORCEPROP 0 LASTPIN (-700 3225) $PN 46
J 0
(-690 3235);
DISPLAY 0.680851 (-690 3235);
PAINT MONO (-690 3235);
FORCEPROP 0 LASTPIN (-700 3275) $PN 48
J 0
(-690 3285);
DISPLAY 0.680851 (-690 3285);
PAINT MONO (-690 3285);
FORCEPROP 0 LASTPIN (-700 3325) $PN 50
J 0
(-690 3335);
DISPLAY 0.680851 (-690 3335);
PAINT MONO (-690 3335);
FORCEPROP 0 LASTPIN (-700 3375) $PN 52
J 0
(-690 3385);
DISPLAY 0.680851 (-690 3385);
PAINT MONO (-690 3385);
FORCEPROP 0 LASTPIN (-700 3425) $PN 54
J 0
(-690 3435);
DISPLAY 0.680851 (-690 3435);
PAINT MONO (-690 3435);
FORCEPROP 0 LASTPIN (-700 3475) $PN 57
J 0
(-690 3485);
DISPLAY 0.680851 (-690 3485);
PAINT MONO (-690 3485);
FORCEPROP 0 LASTPIN (-700 3525) $PN 59
J 0
(-690 3535);
DISPLAY 0.680851 (-690 3535);
PAINT MONO (-690 3535);
FORCEPROP 0 LASTPIN (-700 3575) $PN 61
J 0
(-690 3585);
DISPLAY 0.680851 (-690 3585);
PAINT MONO (-690 3585);
FORCEPROP 0 LASTPIN (-700 3625) $PN 63
J 0
(-690 3635);
DISPLAY 0.680851 (-690 3635);
PAINT MONO (-690 3635);
FORCEPROP 0 LASTPIN (-700 3675) $PN 65
J 0
(-690 3685);
DISPLAY 0.680851 (-690 3685);
PAINT MONO (-690 3685);
FORCEPROP 0 LASTPIN (-700 3725) $PN 67
J 0
(-690 3735);
DISPLAY 0.680851 (-690 3735);
PAINT MONO (-690 3735);
FORCEPROP 0 LASTPIN (-700 3775) $PN 69
J 0
(-690 3785);
DISPLAY 0.680851 (-690 3785);
PAINT MONO (-690 3785);
FORCEPROP 0 LASTPIN (-700 3825) $PN 71
J 0
(-690 3835);
DISPLAY 0.680851 (-690 3835);
PAINT MONO (-690 3835);
FORCEPROP 0 LASTPIN (-700 3875) $PN 73
J 0
(-690 3885);
DISPLAY 0.680851 (-690 3885);
PAINT MONO (-690 3885);
FORCEPROP 0 LASTPIN (-700 3925) $PN 75
J 0
(-690 3935);
DISPLAY 0.680851 (-690 3935);
PAINT MONO (-690 3935);
FORCEPROP 0 LASTPIN (-700 3975) $PN 77
J 0
(-690 3985);
DISPLAY 0.680851 (-690 3985);
PAINT MONO (-690 3985);
FORCEPROP 0 LASTPIN (-700 4025) $PN 79
J 0
(-690 4035);
DISPLAY 0.680851 (-690 4035);
PAINT MONO (-690 4035);
FORCEPROP 0 LASTPIN (-700 4075) $PN 81
J 0
(-690 4085);
DISPLAY 0.680851 (-690 4085);
PAINT MONO (-690 4085);
FORCEPROP 0 LASTPIN (-700 4125) $PN 83
J 0
(-690 4135);
DISPLAY 0.680851 (-690 4135);
PAINT MONO (-690 4135);
FORCEPROP 0 LASTPIN (-700 4175) $PN 85
J 0
(-690 4185);
DISPLAY 0.680851 (-690 4185);
PAINT MONO (-690 4185);
FORCEPROP 0 LASTPIN (-700 4225) $PN 88
J 0
(-690 4235);
DISPLAY 0.680851 (-690 4235);
PAINT MONO (-690 4235);
FORCEPROP 0 LASTPIN (-700 4275) $PN 90
J 0
(-690 4285);
DISPLAY 0.680851 (-690 4285);
PAINT MONO (-690 4285);
FORCEPROP 0 LASTPIN (-700 4325) $PN 92
J 0
(-690 4335);
DISPLAY 0.680851 (-690 4335);
PAINT MONO (-690 4335);
FORCEPROP 0 LASTPIN (-700 4375) $PN 95
J 0
(-690 4385);
DISPLAY 0.680851 (-690 4385);
PAINT MONO (-690 4385);
FORCEPROP 0 LASTPIN (-700 4425) $PN 97
J 0
(-690 4435);
DISPLAY 0.680851 (-690 4435);
PAINT MONO (-690 4435);
FORCEPROP 0 LASTPIN (-700 4475) $PN 99
J 0
(-690 4485);
DISPLAY 0.680851 (-690 4485);
PAINT MONO (-690 4485);
FORCEPROP 0 LASTPIN (-700 4525) $PN 101
J 0
(-690 4535);
DISPLAY 0.680851 (-690 4535);
PAINT MONO (-690 4535);
FORCEPROP 0 LASTPIN (-700 4575) $PN 103
J 0
(-690 4585);
DISPLAY 0.680851 (-690 4585);
PAINT MONO (-690 4585);
FORCEPROP 0 LASTPIN (-700 4625) $PN 106
J 0
(-690 4635);
DISPLAY 0.680851 (-690 4635);
PAINT MONO (-690 4635);
FORCEPROP 0 LASTPIN (-700 4675) $PN 108
J 0
(-690 4685);
DISPLAY 0.680851 (-690 4685);
PAINT MONO (-690 4685);
FORCEPROP 0 LASTPIN (-700 4725) $PN 110
J 0
(-690 4735);
DISPLAY 0.680851 (-690 4735);
PAINT MONO (-690 4735);
FORCEPROP 0 LASTPIN (-700 4775) $PN 112
J 0
(-690 4785);
DISPLAY 0.680851 (-690 4785);
PAINT MONO (-690 4785);
FORCEPROP 0 LASTPIN (-700 4825) $PN 114
J 0
(-690 4835);
DISPLAY 0.680851 (-690 4835);
PAINT MONO (-690 4835);
FORCEPROP 0 LASTPIN (-700 4875) $PN 117
J 0
(-690 4885);
DISPLAY 0.680851 (-690 4885);
PAINT MONO (-690 4885);
FORCEPROP 0 LASTPIN (-700 4925) $PN 119
J 0
(-690 4935);
DISPLAY 0.680851 (-690 4935);
PAINT MONO (-690 4935);
FORCEPROP 0 LASTPIN (-700 4975) $PN 121
J 0
(-690 4985);
DISPLAY 0.680851 (-690 4985);
PAINT MONO (-690 4985);
FORCEPROP 0 LASTPIN (-700 5025) $PN 123
J 0
(-690 5035);
DISPLAY 0.680851 (-690 5035);
PAINT MONO (-690 5035);
FORCEPROP 0 LASTPIN (-700 5075) $PN 125
J 0
(-690 5085);
DISPLAY 0.680851 (-690 5085);
PAINT MONO (-690 5085);
FORCEPROP 0 LASTPIN (-700 5125) $PN 128
J 0
(-690 5135);
DISPLAY 0.680851 (-690 5135);
PAINT MONO (-690 5135);
FORCEPROP 0 LASTPIN (-700 5175) $PN 130
J 0
(-690 5185);
DISPLAY 0.680851 (-690 5185);
PAINT MONO (-690 5185);
FORCEPROP 0 LASTPIN (-700 5225) $PN 132
J 0
(-690 5235);
DISPLAY 0.680851 (-690 5235);
PAINT MONO (-690 5235);
FORCEPROP 0 LASTPIN (-700 5275) $PN 134
J 0
(-690 5285);
DISPLAY 0.680851 (-690 5285);
PAINT MONO (-690 5285);
FORCEPROP 0 LASTPIN (-700 5325) $PN 136
J 0
(-690 5335);
DISPLAY 0.680851 (-690 5335);
PAINT MONO (-690 5335);
FORCEPROP 0 LASTPIN (-700 5375) $PN 139
J 0
(-690 5385);
DISPLAY 0.680851 (-690 5385);
PAINT MONO (-690 5385);
FORCEPROP 0 LASTPIN (-700 5425) $PN 141
J 0
(-690 5435);
DISPLAY 0.680851 (-690 5435);
PAINT MONO (-690 5435);
FORCEPROP 0 LASTPIN (-700 5475) $PN 143
J 0
(-690 5485);
DISPLAY 0.680851 (-690 5485);
PAINT MONO (-690 5485);
FORCEPROP 0 LASTPIN (-1900 2225) $PN 151
J 2
(-1910 2235);
DISPLAY 0.680851 (-1910 2235);
PAINT MONO (-1910 2235);
FORCEPROP 0 LASTPIN (-1900 2275) $PN 153
J 2
(-1910 2285);
DISPLAY 0.680851 (-1910 2285);
PAINT MONO (-1910 2285);
FORCEPROP 0 LASTPIN (-1900 2325) $PN 155
J 2
(-1910 2335);
DISPLAY 0.680851 (-1910 2335);
PAINT MONO (-1910 2335);
FORCEPROP 0 LASTPIN (-1900 2375) $PN 158
J 2
(-1910 2385);
DISPLAY 0.680851 (-1910 2385);
PAINT MONO (-1910 2385);
FORCEPROP 0 LASTPIN (-1900 2425) $PN 160
J 2
(-1910 2435);
DISPLAY 0.680851 (-1910 2435);
PAINT MONO (-1910 2435);
FORCEPROP 0 LASTPIN (-1900 2475) $PN 162
J 2
(-1910 2485);
DISPLAY 0.680851 (-1910 2485);
PAINT MONO (-1910 2485);
FORCEPROP 0 LASTPIN (-1900 2525) $PN 164
J 2
(-1910 2535);
DISPLAY 0.680851 (-1910 2535);
PAINT MONO (-1910 2535);
FORCEPROP 0 LASTPIN (-1900 2575) $PN 166
J 2
(-1910 2585);
DISPLAY 0.680851 (-1910 2585);
PAINT MONO (-1910 2585);
FORCEPROP 0 LASTPIN (-1900 2625) $PN 169
J 2
(-1910 2635);
DISPLAY 0.680851 (-1910 2635);
PAINT MONO (-1910 2635);
FORCEPROP 0 LASTPIN (-1900 2675) $PN 171
J 2
(-1910 2685);
DISPLAY 0.680851 (-1910 2685);
PAINT MONO (-1910 2685);
FORCEPROP 0 LASTPIN (-1900 2725) $PN 173
J 2
(-1910 2735);
DISPLAY 0.680851 (-1910 2735);
PAINT MONO (-1910 2735);
FORCEPROP 0 LASTPIN (-1900 2775) $PN 175
J 2
(-1910 2785);
DISPLAY 0.680851 (-1910 2785);
PAINT MONO (-1910 2785);
FORCEPROP 0 LASTPIN (-1900 2825) $PN 177
J 2
(-1910 2835);
DISPLAY 0.680851 (-1910 2835);
PAINT MONO (-1910 2835);
FORCEPROP 0 LASTPIN (-1900 2875) $PN 180
J 2
(-1910 2885);
DISPLAY 0.680851 (-1910 2885);
PAINT MONO (-1910 2885);
FORCEPROP 0 LASTPIN (-1900 2925) $PN 182
J 2
(-1910 2935);
DISPLAY 0.680851 (-1910 2935);
PAINT MONO (-1910 2935);
FORCEPROP 0 LASTPIN (-1900 2975) $PN 184
J 2
(-1910 2985);
DISPLAY 0.680851 (-1910 2985);
PAINT MONO (-1910 2985);
FORCEPROP 0 LASTPIN (-1900 3025) $PN 186
J 2
(-1910 3035);
DISPLAY 0.680851 (-1910 3035);
PAINT MONO (-1910 3035);
FORCEPROP 0 LASTPIN (-1900 3075) $PN 188
J 2
(-1910 3085);
DISPLAY 0.680851 (-1910 3085);
PAINT MONO (-1910 3085);
FORCEPROP 0 LASTPIN (-1900 3125) $PN 191
J 2
(-1910 3135);
DISPLAY 0.680851 (-1910 3135);
PAINT MONO (-1910 3135);
FORCEPROP 0 LASTPIN (-1900 3175) $PN 193
J 2
(-1910 3185);
DISPLAY 0.680851 (-1910 3185);
PAINT MONO (-1910 3185);
FORCEPROP 0 LASTPIN (-1900 3225) $PN 195
J 2
(-1910 3235);
DISPLAY 0.680851 (-1910 3235);
PAINT MONO (-1910 3235);
FORCEPROP 0 LASTPIN (-1900 3275) $PN 197
J 2
(-1910 3285);
DISPLAY 0.680851 (-1910 3285);
PAINT MONO (-1910 3285);
FORCEPROP 0 LASTPIN (-1900 3325) $PN 199
J 2
(-1910 3335);
DISPLAY 0.680851 (-1910 3335);
PAINT MONO (-1910 3335);
FORCEPROP 0 LASTPIN (-1900 3375) $PN 202
J 2
(-1910 3385);
DISPLAY 0.680851 (-1910 3385);
PAINT MONO (-1910 3385);
FORCEPROP 0 LASTPIN (-1900 3425) $PN 204
J 2
(-1910 3435);
DISPLAY 0.680851 (-1910 3435);
PAINT MONO (-1910 3435);
FORCEPROP 0 LASTPIN (-1900 3475) $PN 206
J 2
(-1910 3485);
DISPLAY 0.680851 (-1910 3485);
PAINT MONO (-1910 3485);
FORCEPROP 0 LASTPIN (-1900 3525) $PN 208
J 2
(-1910 3535);
DISPLAY 0.680851 (-1910 3535);
PAINT MONO (-1910 3535);
FORCEPROP 0 LASTPIN (-1900 3575) $PN 210
J 2
(-1910 3585);
DISPLAY 0.680851 (-1910 3585);
PAINT MONO (-1910 3585);
FORCEPROP 0 LASTPIN (-1900 3625) $PN 212
J 2
(-1910 3635);
DISPLAY 0.680851 (-1910 3635);
PAINT MONO (-1910 3635);
FORCEPROP 0 LASTPIN (-1900 3675) $PN 214
J 2
(-1910 3685);
DISPLAY 0.680851 (-1910 3685);
PAINT MONO (-1910 3685);
FORCEPROP 0 LASTPIN (-1900 3725) $PN 216
J 2
(-1910 3735);
DISPLAY 0.680851 (-1910 3735);
PAINT MONO (-1910 3735);
FORCEPROP 0 LASTPIN (-1900 3775) $PN 219
J 2
(-1910 3785);
DISPLAY 0.680851 (-1910 3785);
PAINT MONO (-1910 3785);
FORCEPROP 0 LASTPIN (-1900 3825) $PN 222
J 2
(-1910 3835);
DISPLAY 0.680851 (-1910 3835);
PAINT MONO (-1910 3835);
FORCEPROP 0 LASTPIN (-1900 3875) $PN 224
J 2
(-1910 3885);
DISPLAY 0.680851 (-1910 3885);
PAINT MONO (-1910 3885);
FORCEPROP 0 LASTPIN (-1900 3925) $PN 226
J 2
(-1910 3935);
DISPLAY 0.680851 (-1910 3935);
PAINT MONO (-1910 3935);
FORCEPROP 0 LASTPIN (-1900 3975) $PN 228
J 2
(-1910 3985);
DISPLAY 0.680851 (-1910 3985);
PAINT MONO (-1910 3985);
FORCEPROP 0 LASTPIN (-1900 4025) $PN 230
J 2
(-1910 4035);
DISPLAY 0.680851 (-1910 4035);
PAINT MONO (-1910 4035);
FORCEPROP 0 LASTPIN (-1900 4075) $PN 233
J 2
(-1910 4085);
DISPLAY 0.680851 (-1910 4085);
PAINT MONO (-1910 4085);
FORCEPROP 0 LASTPIN (-1900 4125) $PN 235
J 2
(-1910 4135);
DISPLAY 0.680851 (-1910 4135);
PAINT MONO (-1910 4135);
FORCEPROP 0 LASTPIN (-1900 4175) $PN 237
J 2
(-1910 4185);
DISPLAY 0.680851 (-1910 4185);
PAINT MONO (-1910 4185);
FORCEPROP 0 LASTPIN (-1900 4225) $PN 240
J 2
(-1910 4235);
DISPLAY 0.680851 (-1910 4235);
PAINT MONO (-1910 4235);
FORCEPROP 0 LASTPIN (-1900 4275) $PN 242
J 2
(-1910 4285);
DISPLAY 0.680851 (-1910 4285);
PAINT MONO (-1910 4285);
FORCEPROP 0 LASTPIN (-1900 4325) $PN 244
J 2
(-1910 4335);
DISPLAY 0.680851 (-1910 4335);
PAINT MONO (-1910 4335);
FORCEPROP 0 LASTPIN (-1900 4375) $PN 246
J 2
(-1910 4385);
DISPLAY 0.680851 (-1910 4385);
PAINT MONO (-1910 4385);
FORCEPROP 0 LASTPIN (-1900 4425) $PN 248
J 2
(-1910 4435);
DISPLAY 0.680851 (-1910 4435);
PAINT MONO (-1910 4435);
FORCEPROP 0 LASTPIN (-1900 4475) $PN 251
J 2
(-1910 4485);
DISPLAY 0.680851 (-1910 4485);
PAINT MONO (-1910 4485);
FORCEPROP 0 LASTPIN (-1900 4525) $PN 253
J 2
(-1910 4535);
DISPLAY 0.680851 (-1910 4535);
PAINT MONO (-1910 4535);
FORCEPROP 0 LASTPIN (-1900 4575) $PN 255
J 2
(-1910 4585);
DISPLAY 0.680851 (-1910 4585);
PAINT MONO (-1910 4585);
FORCEPROP 0 LASTPIN (-1900 4625) $PN 257
J 2
(-1910 4635);
DISPLAY 0.680851 (-1910 4635);
PAINT MONO (-1910 4635);
FORCEPROP 0 LASTPIN (-1900 4675) $PN 259
J 2
(-1910 4685);
DISPLAY 0.680851 (-1910 4685);
PAINT MONO (-1910 4685);
FORCEPROP 0 LASTPIN (-1900 4725) $PN 262
J 2
(-1910 4735);
DISPLAY 0.680851 (-1910 4735);
PAINT MONO (-1910 4735);
FORCEPROP 0 LASTPIN (-1900 4775) $PN 264
J 2
(-1910 4785);
DISPLAY 0.680851 (-1910 4785);
PAINT MONO (-1910 4785);
FORCEPROP 0 LASTPIN (-1900 4825) $PN 266
J 2
(-1910 4835);
DISPLAY 0.680851 (-1910 4835);
PAINT MONO (-1910 4835);
FORCEPROP 0 LASTPIN (-1900 4875) $PN 268
J 2
(-1910 4885);
DISPLAY 0.680851 (-1910 4885);
PAINT MONO (-1910 4885);
FORCEPROP 0 LASTPIN (-1900 4925) $PN 270
J 2
(-1910 4935);
DISPLAY 0.680851 (-1910 4935);
PAINT MONO (-1910 4935);
FORCEPROP 0 LASTPIN (-1900 4975) $PN 273
J 2
(-1910 4985);
DISPLAY 0.680851 (-1910 4985);
PAINT MONO (-1910 4985);
FORCEPROP 0 LASTPIN (-1900 5025) $PN 275
J 2
(-1910 5035);
DISPLAY 0.680851 (-1910 5035);
PAINT MONO (-1910 5035);
FORCEPROP 0 LASTPIN (-1900 5075) $PN 277
J 2
(-1910 5085);
DISPLAY 0.680851 (-1910 5085);
PAINT MONO (-1910 5085);
FORCEPROP 0 LASTPIN (-1900 5125) $PN 279
J 2
(-1910 5135);
DISPLAY 0.680851 (-1910 5135);
PAINT MONO (-1910 5135);
FORCEPROP 0 LASTPIN (-1900 5175) $PN 281
J 2
(-1910 5185);
DISPLAY 0.680851 (-1910 5185);
PAINT MONO (-1910 5185);
FORCEPROP 0 LASTPIN (-1900 5225) $PN 284
J 2
(-1910 5235);
DISPLAY 0.680851 (-1910 5235);
PAINT MONO (-1910 5235);
FORCEPROP 0 LASTPIN (-1900 5275) $PN 286
J 2
(-1910 5285);
DISPLAY 0.680851 (-1910 5285);
PAINT MONO (-1910 5285);
FORCEPROP 0 LASTPIN (-1900 5325) $PN 288
J 2
(-1910 5335);
DISPLAY 0.680851 (-1910 5335);
PAINT MONO (-1910 5335);
FORCEPROP 2 LAST VALUE SCONN288_DDR506112002KQ
J 0
(-1750 5850);
DISPLAY 0.489362 (-1750 5850);
PAINT SKYBLUE (-1750 5850);
FORCEPROP 1 LAST MATERIAL IO
J 0
(-1750 5650);
DISPLAY 0.468085 (-1750 5650);
PAINT SKYBLUE (-1750 5650);
FORCEPROP 2 LAST PART_TYPE SMLF
J 0
(-1750 5900);
DISPLAY 1.021277 (-1750 5900);
FORCEPROP 1 LAST CDS_LMAN_SYM_OUTLINE -450,1800,450,-1750
J 0
(-1300 3825);
DISPLAY 0.468085 (-1300 3825);
PAINT GREEN (-1300 3825);
DISPLAY INVISIBLE (-1300 3825);
FORCEPROP 1 LAST NEEDS_NO_SIZE TRUE
J 0
(-1300 3825);
DISPLAY 0.723404 (-1300 3825);
PAINT GREEN (-1300 3825);
DISPLAY INVISIBLE (-1300 3825);
FORCEPROP 2 LAST CDS_LIB pure_quanta
J 0
(-1300 3825);
DISPLAY INVISIBLE (-1300 3825);
FORCEPROP 1 LAST PATH I177
J 0
(-1300 3825);
DISPLAY 0.723404 (-1300 3825);
PAINT GREEN (-1300 3825);
DISPLAY INVISIBLE (-1300 3825);
FORCEPROP 1 LAST PART_NUMBER DFHST8FS479
J 0
(-1750 5725);
DISPLAY 0.468085 (-1750 5725);
PAINT SKYBLUE (-1750 5725);
DISPLAY INVISIBLE (-1750 5725);
FORCEADD OFFPAGE..1
(-8050 4525);
FORCEPROP 2 LAST $XR0 37 
J 0
(-8271 4525);
DISPLAY 0.638298 (-8271 4525);
PAINT MONO (-8271 4525);
FORCEPROP 2 LAST CDS_LIB mstr_standard
J 0
(-8050 4525);
DISPLAY 0.723404 (-8050 4525);
PAINT MONO (-8050 4525);
DISPLAY INVISIBLE (-8050 4525);
FORCEPROP 1 LAST OFFPAGE TRUE
J 0
(-7725 4400);
DISPLAY 0.872340 (-7725 4400);
PAINT GREEN (-7725 4400);
DISPLAY INVISIBLE (-7725 4400);
FORCEPROP 1 LAST COMMENT_BODY TRUE
J 0
(-7925 4425);
DISPLAY 0.872340 (-7925 4425);
PAINT GREEN (-7925 4425);
DISPLAY INVISIBLE (-7925 4425);
FORCEPROP 2 LAST PATH I18
J 0
(-8300 4575);
DISPLAY 1.021277 (-8300 4575);
DISPLAY INVISIBLE (-8300 4575);
FORCEADD Q_CAP..1
R 2
(-8600 3325);
FORCEPROP 1 LAST LOCATION C136
J 2
(-8650 3425);
DISPLAY 0.489362 (-8650 3425);
PAINT SKYBLUE (-8650 3425);
FORCEPROP 0 LAST $SEC 1
J 0
(-8650 3475);
DISPLAY 0.680851 (-8650 3475);
PAINT MONO (-8650 3475);
DISPLAY INVISIBLE (-8650 3475);
FORCEPROP 0 LAST CDS_SEC 1
J 0
(-8650 3475);
DISPLAY 1.021277 (-8650 3475);
DISPLAY INVISIBLE (-8650 3475);
FORCEPROP 1 LASTPIN (-8600 3425) $PN 1
J 2
(-8610 3405);
DISPLAY 0.489362 (-8610 3405);
PAINT MONO (-8610 3405);
FORCEPROP 1 LASTPIN (-8600 3225) $PN 2
J 2
(-8610 3205);
DISPLAY 0.489362 (-8610 3205);
PAINT MONO (-8610 3205);
FORCEPROP 1 LAST PACK_TYPE 0402
J 2
(-8650 3125);
DISPLAY 0.489362 (-8650 3125);
PAINT SKYBLUE (-8650 3125);
FORCEPROP 1 LAST VOLTAGE 25V
J 2
(-8650 3325);
DISPLAY 0.489362 (-8650 3325);
PAINT SKYBLUE (-8650 3325);
FORCEPROP 1 LAST VALUE 0.1UF
J 2
(-8650 3375);
DISPLAY 0.489362 (-8650 3375);
PAINT SKYBLUE (-8650 3375);
FORCEPROP 1 LAST TOLERANCE 10%
J 2
(-8650 3275);
DISPLAY 0.489362 (-8650 3275);
PAINT SKYBLUE (-8650 3275);
FORCEPROP 1 LAST MATERIAL X7R
J 2
(-8650 3225);
DISPLAY 0.489362 (-8650 3225);
PAINT SKYBLUE (-8650 3225);
FORCEPROP 0 LAST BOM_COST MEM
J 2
(-8655 3470);
DISPLAY 0.595745 (-8655 3470);
PAINT MONO (-8655 3470);
DISPLAY INVISIBLE (-8655 3470);
FORCEPROP 2 LAST CDS_LIB pure_quanta
J 0
(-8600 3325);
DISPLAY INVISIBLE (-8600 3325);
FORCEPROP 2 LAST ROOM 
J 2
(-8655 3470);
DISPLAY 0.595745 (-8655 3470);
PAINT RED (-8655 3470);
DISPLAY INVISIBLE (-8655 3470);
FORCEPROP 1 LAST PATH I185
J 2
(-8650 3475);
DISPLAY 0.978723 (-8650 3475);
PAINT WHITE (-8650 3475);
DISPLAY INVISIBLE (-8650 3475);
FORCEPROP 1 LAST PART_NUMBER CH4104K1B00
J 2
(-8650 3175);
DISPLAY 0.489362 (-8650 3175);
PAINT SKYBLUE (-8650 3175);
DISPLAY INVISIBLE (-8650 3175);
FORCEADD GND..1
(-8600 3100);
FORCEPROP 3 LASTPIN (-8600 3150) SIG_NAME GND\g
J 0
(-8590 3160);
DISPLAY 0.659574 (-8590 3160);
PAINT MONO (-8590 3160);
DISPLAY INVISIBLE (-8590 3160);
FORCEPROP 2 LAST CDS_LIB mstr_symbols
J 0
(-8600 3100);
DISPLAY 0.808511 (-8600 3100);
DISPLAY INVISIBLE (-8600 3100);
FORCEPROP 1 LAST SIZE 1B
J 0
(-8525 3050);
DISPLAY 0.723404 (-8525 3050);
PAINT GREEN (-8525 3050);
DISPLAY INVISIBLE (-8525 3050);
FORCEPROP 2 LAST BOM_COST MEM
J 0
(-8575 3225);
DISPLAY 0.659574 (-8575 3225);
DISPLAY INVISIBLE (-8575 3225);
FORCEPROP 1 LAST VOLTAGE 0
J 0
(-8620 3195);
DISPLAY 0.829787 (-8620 3195);
PAINT SKYBLUE (-8620 3195);
DISPLAY INVISIBLE (-8620 3195);
FORCEPROP 2 LAST ROOM MEM_EFGH_DECOUPLING_CAPS
J 0
(-8575 3175);
DISPLAY 0.659574 (-8575 3175);
PAINT RED (-8575 3175);
DISPLAY INVISIBLE (-8575 3175);
FORCEPROP 1 LAST BODY_TYPE PLUMBING
J 0
(-8645 3057);
DISPLAY 0.276596 (-8645 3057);
PAINT GREEN (-8645 3057);
DISPLAY INVISIBLE (-8645 3057);
FORCEPROP 1 LAST HDL_POWER GND
J 0
(-8600 3250);
DISPLAY 0.723404 (-8600 3250);
PAINT GREEN (-8600 3250);
DISPLAY INVISIBLE (-8600 3250);
FORCEPROP 1 LAST PATH I186
J 0
(-8525 3100);
DISPLAY 0.872340 (-8525 3100);
PAINT AQUA (-8525 3100);
DISPLAY INVISIBLE (-8525 3100);
FORCEADD OFFPAGE..6
(-8950 2225);
FORCEPROP 2 LAST $XR5 103 
J 0
(-9229 2261);
DISPLAY 0.638298 (-9229 2261);
PAINT MONO (-9229 2261);
FORCEPROP 2 LAST $XR4 102 
J 0
(-9439 2189);
DISPLAY 0.638298 (-9439 2189);
PAINT MONO (-9439 2189);
FORCEPROP 2 LAST $XR3 101 
J 0
(-9319 2189);
DISPLAY 0.638298 (-9319 2189);
PAINT MONO (-9319 2189);
FORCEPROP 2 LAST $XR2 100 
J 0
(-9439 2225);
DISPLAY 0.638298 (-9439 2225);
PAINT MONO (-9439 2225);
FORCEPROP 2 LAST $XR1 99 
J 0
(-9319 2225);
DISPLAY 0.638298 (-9319 2225);
PAINT MONO (-9319 2225);
FORCEPROP 2 LAST $XR0 98 
J 0
(-9229 2225);
DISPLAY 0.638298 (-9229 2225);
PAINT MONO (-9229 2225);
FORCEPROP 2 LAST CDS_LIB mstr_standard
J 0
(-8950 2225);
DISPLAY 0.808511 (-8950 2225);
DISPLAY INVISIBLE (-8950 2225);
FORCEPROP 1 LAST OFFPAGE TRUE
J 0
(-8625 2100);
DISPLAY 0.872340 (-8625 2100);
PAINT GREEN (-8625 2100);
DISPLAY INVISIBLE (-8625 2100);
FORCEPROP 1 LAST COMMENT_BODY TRUE
J 0
(-8850 2150);
DISPLAY 0.872340 (-8850 2150);
PAINT GREEN (-8850 2150);
DISPLAY INVISIBLE (-8850 2150);
FORCEPROP 2 LAST PATH I187
J 0
(-8900 2300);
DISPLAY 1.021277 (-8900 2300);
DISPLAY INVISIBLE (-8900 2300);
FORCEADD VCC_CORE..1
(-8525 2550);
FORCEPROP 3 LASTPIN (-8525 2500) SIG_NAME P3V3\g
J 0
(-8515 2510);
DISPLAY 0.659574 (-8515 2510);
PAINT MONO (-8515 2510);
DISPLAY INVISIBLE (-8515 2510);
FORCEPROP 1 LAST HDL_POWER P3V3
J 1
(-8525 2600);
DISPLAY 0.489362 (-8525 2600);
PAINT GREEN (-8525 2600);
FORCEPROP 2 LAST CDS_LIB mstr_symbols
J 0
(-8525 2550);
DISPLAY INVISIBLE (-8525 2550);
FORCEPROP 0 LAST VOLTAGE 3.3
J 0
(-8800 2700);
DISPLAY 1.021277 (-8800 2700);
PAINT SKYBLUE (-8800 2700);
DISPLAY INVISIBLE (-8800 2700);
FORCEPROP 2 LAST ROOM PVCCINFAON_CPU0_CTRL
J 0
(-8525 2650);
DISPLAY 0.808511 (-8525 2650);
PAINT RED (-8525 2650);
DISPLAY INVISIBLE (-8525 2650);
FORCEPROP 1 LAST PATH I188
J 0
(-8475 2575);
DISPLAY 0.872340 (-8475 2575);
PAINT AQUA (-8475 2575);
DISPLAY INVISIBLE (-8475 2575);
FORCEADD Q_RES..2
R 2
(-8525 2375);
FORCEPROP 1 LAST LOCATION R102
J 2
(-8570 2500);
DISPLAY 0.489362 (-8570 2500);
PAINT SKYBLUE (-8570 2500);
FORCEPROP 0 LAST $SEC 1
J 0
(-8550 2550);
DISPLAY 0.680851 (-8550 2550);
PAINT MONO (-8550 2550);
DISPLAY INVISIBLE (-8550 2550);
FORCEPROP 0 LAST CDS_SEC 1
J 0
(-8550 2550);
DISPLAY 1.021277 (-8550 2550);
DISPLAY INVISIBLE (-8550 2550);
FORCEPROP 1 LASTPIN (-8525 2475) $PN 1
J 2
(-8530 2437);
DISPLAY 0.489362 (-8530 2437);
PAINT MONO (-8530 2437);
FORCEPROP 1 LASTPIN (-8525 2275) $PN 2
J 2
(-8530 2285);
DISPLAY 0.489362 (-8530 2285);
PAINT MONO (-8530 2285);
FORCEPROP 1 LAST TOLERANCE 1%
J 2
(-8575 2425);
DISPLAY 0.489362 (-8575 2425);
PAINT SKYBLUE (-8575 2425);
FORCEPROP 1 LAST WATTAGE 1/16W
J 2
(-8575 2400);
DISPLAY 0.489362 (-8575 2400);
PAINT SKYBLUE (-8575 2400);
FORCEPROP 1 LAST VALUE 1K
J 2
(-8570 2450);
DISPLAY 0.489362 (-8570 2450);
PAINT SKYBLUE (-8570 2450);
FORCEPROP 1 LAST PACK_TYPE 0402LF
J 2
(-8575 2325);
DISPLAY 0.489362 (-8575 2325);
PAINT SKYBLUE (-8575 2325);
FORCEPROP 1 LAST MATERIAL EMPTY
J 2
(-8575 2375);
DISPLAY 0.489362 (-8575 2375);
PAINT RED (-8575 2375);
FORCEPROP 2 LAST BOM_COST MEM
J 2
(-8575 2550);
DISPLAY 0.808511 (-8575 2550);
DISPLAY INVISIBLE (-8575 2550);
FORCEPROP 2 LAST CDS_LIB pure_quanta
J 2
(-8525 2375);
DISPLAY INVISIBLE (-8525 2375);
FORCEPROP 2 LAST ROOM 
J 2
(-8575 2600);
DISPLAY 0.808511 (-8575 2600);
PAINT RED (-8575 2600);
DISPLAY INVISIBLE (-8575 2600);
FORCEPROP 1 LAST PATH I189
J 2
(-8575 2550);
DISPLAY 0.978723 (-8575 2550);
PAINT WHITE (-8575 2550);
DISPLAY INVISIBLE (-8575 2550);
FORCEPROP 1 LAST PART_NUMBER CS21002FB06
J 2
(-8575 2350);
DISPLAY 0.489362 (-8575 2350);
PAINT SKYBLUE (-8575 2350);
DISPLAY INVISIBLE (-8575 2350);
FORCEADD OFFPAGE..1
(-8050 4675);
FORCEPROP 2 LAST $XR0 37 
J 0
(-8271 4675);
DISPLAY 0.638298 (-8271 4675);
PAINT MONO (-8271 4675);
FORCEPROP 2 LAST CDS_LIB mstr_standard
J 0
(-8050 4675);
DISPLAY 0.723404 (-8050 4675);
PAINT MONO (-8050 4675);
DISPLAY INVISIBLE (-8050 4675);
FORCEPROP 1 LAST OFFPAGE TRUE
J 0
(-7725 4550);
DISPLAY 0.872340 (-7725 4550);
PAINT GREEN (-7725 4550);
DISPLAY INVISIBLE (-7725 4550);
FORCEPROP 1 LAST COMMENT_BODY TRUE
J 0
(-7925 4575);
DISPLAY 0.872340 (-7925 4575);
PAINT GREEN (-7925 4575);
DISPLAY INVISIBLE (-7925 4575);
FORCEPROP 2 LAST PATH I19
J 0
(-8300 4725);
DISPLAY 1.021277 (-8300 4725);
DISPLAY INVISIBLE (-8300 4725);
FORCEADD Q_RES..1
R 2
(-8400 2225);
FORCEPROP 1 LAST LOCATION R303
J 2
(-8375 2250);
DISPLAY 0.489362 (-8375 2250);
PAINT SKYBLUE (-8375 2250);
FORCEPROP 0 LAST $SEC 1
J 0
(-8375 2300);
DISPLAY 0.680851 (-8375 2300);
PAINT MONO (-8375 2300);
DISPLAY INVISIBLE (-8375 2300);
FORCEPROP 0 LAST CDS_SEC 1
J 0
(-8375 2300);
DISPLAY 1.021277 (-8375 2300);
DISPLAY INVISIBLE (-8375 2300);
FORCEPROP 1 LASTPIN (-8300 2225) $PN 1
J 2
(-8312 2237);
DISPLAY 0.489362 (-8312 2237);
PAINT MONO (-8312 2237);
FORCEPROP 1 LASTPIN (-8500 2225) $PN 2
J 2
(-8462 2237);
DISPLAY 0.489362 (-8462 2237);
PAINT MONO (-8462 2237);
FORCEPROP 1 LAST VALUE 1K
J 0
(-8400 2175);
DISPLAY 0.489362 (-8400 2175);
PAINT SKYBLUE (-8400 2175);
FORCEPROP 1 LAST TOLERANCE 1%
J 2
(-8275 2200);
DISPLAY 0.489362 (-8275 2200);
PAINT SKYBLUE (-8275 2200);
DISPLAY INVISIBLE (-8275 2200);
FORCEPROP 2 LAST CDS_LIB pure_quanta
J 0
(-8400 2225);
DISPLAY INVISIBLE (-8400 2225);
FORCEPROP 2 LAST BOM_COST MEM
J 0
(-8425 2375);
DISPLAY 0.744681 (-8425 2375);
PAINT WHITE (-8425 2375);
DISPLAY INVISIBLE (-8425 2375);
FORCEPROP 1 LAST WATTAGE 1/16W
J 0
(-8325 2150);
DISPLAY 0.489362 (-8325 2150);
PAINT SKYBLUE (-8325 2150);
DISPLAY INVISIBLE (-8325 2150);
FORCEPROP 1 LAST MATERIAL CHIP
J 0
(-8575 2200);
DISPLAY 0.489362 (-8575 2200);
PAINT SKYBLUE (-8575 2200);
DISPLAY INVISIBLE (-8575 2200);
FORCEPROP 1 LAST PACK_TYPE 0402LF
J 0
(-8575 2150);
DISPLAY 0.489362 (-8575 2150);
PAINT SKYBLUE (-8575 2150);
DISPLAY INVISIBLE (-8575 2150);
FORCEPROP 2 LAST ROOM 
J 0
(-8425 2325);
DISPLAY 0.744681 (-8425 2325);
PAINT RED (-8425 2325);
DISPLAY INVISIBLE (-8425 2325);
FORCEPROP 1 LAST PATH I190
J 2
(-8350 2375);
DISPLAY 0.978723 (-8350 2375);
PAINT WHITE (-8350 2375);
DISPLAY INVISIBLE (-8350 2375);
FORCEPROP 1 LAST PART_NUMBER CS21002FB06
J 0
(-8500 2275);
DISPLAY 0.489362 (-8500 2275);
PAINT SKYBLUE (-8500 2275);
DISPLAY INVISIBLE (-8500 2275);
FORCEADD Q_RES..2
(-8275 2375);
FORCEPROP 1 LAST LOCATION R103
J 0
(-8230 2500);
DISPLAY 0.489362 (-8230 2500);
PAINT SKYBLUE (-8230 2500);
FORCEPROP 0 LAST $SEC 1
J 0
(-8225 2550);
DISPLAY 0.680851 (-8225 2550);
PAINT MONO (-8225 2550);
DISPLAY INVISIBLE (-8225 2550);
FORCEPROP 0 LAST CDS_SEC 1
J 0
(-8225 2550);
DISPLAY 1.021277 (-8225 2550);
DISPLAY INVISIBLE (-8225 2550);
FORCEPROP 1 LASTPIN (-8275 2475) $PN 1
J 0
(-8270 2437);
DISPLAY 0.489362 (-8270 2437);
PAINT MONO (-8270 2437);
FORCEPROP 1 LASTPIN (-8275 2275) $PN 2
J 0
(-8270 2285);
DISPLAY 0.489362 (-8270 2285);
PAINT MONO (-8270 2285);
FORCEPROP 1 LAST VALUE 1K
J 0
(-8230 2450);
DISPLAY 0.489362 (-8230 2450);
PAINT SKYBLUE (-8230 2450);
FORCEPROP 1 LAST PACK_TYPE 0402LF
J 0
(-8225 2325);
DISPLAY 0.489362 (-8225 2325);
PAINT SKYBLUE (-8225 2325);
FORCEPROP 1 LAST MATERIAL EMPTY
J 0
(-8225 2375);
DISPLAY 0.489362 (-8225 2375);
PAINT RED (-8225 2375);
FORCEPROP 1 LAST WATTAGE 1/16W
J 0
(-8225 2400);
DISPLAY 0.489362 (-8225 2400);
PAINT SKYBLUE (-8225 2400);
FORCEPROP 1 LAST TOLERANCE 1%
J 0
(-8225 2425);
DISPLAY 0.489362 (-8225 2425);
PAINT SKYBLUE (-8225 2425);
FORCEPROP 2 LAST BOM_COST MEM
J 0
(-8225 2550);
DISPLAY 0.808511 (-8225 2550);
DISPLAY INVISIBLE (-8225 2550);
FORCEPROP 2 LAST CDS_LIB pure_quanta
J 2
(-8275 2375);
DISPLAY INVISIBLE (-8275 2375);
FORCEPROP 2 LAST ROOM 
J 0
(-8225 2600);
DISPLAY 0.808511 (-8225 2600);
PAINT RED (-8225 2600);
DISPLAY INVISIBLE (-8225 2600);
FORCEPROP 1 LAST PATH I191
J 0
(-8225 2550);
DISPLAY 0.978723 (-8225 2550);
PAINT WHITE (-8225 2550);
DISPLAY INVISIBLE (-8225 2550);
FORCEPROP 1 LAST PART_NUMBER CS21002FB06
J 0
(-8225 2350);
DISPLAY 0.489362 (-8225 2350);
PAINT SKYBLUE (-8225 2350);
DISPLAY INVISIBLE (-8225 2350);
FORCEADD VCC_CORE..1
(-8275 2550);
FORCEPROP 3 LASTPIN (-8275 2500) SIG_NAME P3V3\g
J 0
(-8265 2510);
DISPLAY 0.659574 (-8265 2510);
PAINT MONO (-8265 2510);
DISPLAY INVISIBLE (-8265 2510);
FORCEPROP 1 LAST HDL_POWER P3V3
J 1
(-8275 2600);
DISPLAY 0.489362 (-8275 2600);
PAINT GREEN (-8275 2600);
FORCEPROP 2 LAST CDS_LIB mstr_symbols
J 0
(-8275 2550);
DISPLAY INVISIBLE (-8275 2550);
FORCEPROP 0 LAST VOLTAGE 3.3
J 0
(-8550 2700);
DISPLAY 1.021277 (-8550 2700);
PAINT SKYBLUE (-8550 2700);
DISPLAY INVISIBLE (-8550 2700);
FORCEPROP 2 LAST ROOM PVCCINFAON_CPU0_CTRL
J 0
(-8275 2650);
DISPLAY 0.808511 (-8275 2650);
PAINT RED (-8275 2650);
DISPLAY INVISIBLE (-8275 2650);
FORCEPROP 1 LAST PATH I192
J 0
(-8225 2575);
DISPLAY 0.872340 (-8225 2575);
PAINT AQUA (-8225 2575);
DISPLAY INVISIBLE (-8225 2575);
FORCEADD OFFPAGE..2
(-2425 4650);
FORCEPROP 2 LAST $XR0 37 
J 0
(-2236 4650);
DISPLAY 0.638298 (-2236 4650);
PAINT MONO (-2236 4650);
FORCEPROP 2 LAST CDS_LIB mstr_standard
J 0
(-2425 4650);
DISPLAY 0.723404 (-2425 4650);
PAINT MONO (-2425 4650);
DISPLAY INVISIBLE (-2425 4650);
FORCEPROP 1 LAST OFFPAGE TRUE
J 0
(-2100 4525);
DISPLAY 0.723404 (-2100 4525);
PAINT GREEN (-2100 4525);
DISPLAY INVISIBLE (-2100 4525);
FORCEPROP 1 LAST COMMENT_BODY TRUE
J 0
(-2470 4555);
DISPLAY 0.872340 (-2470 4555);
PAINT GREEN (-2470 4555);
DISPLAY INVISIBLE (-2470 4555);
FORCEPROP 2 LAST PATH I194
J 0
(-2225 4700);
DISPLAY 0.680851 (-2225 4700);
DISPLAY INVISIBLE (-2225 4700);
FORCEADD OFFPAGE..2
(-2425 4600);
FORCEPROP 2 LAST $XR0 37 
J 0
(-2236 4600);
DISPLAY 0.638298 (-2236 4600);
PAINT MONO (-2236 4600);
FORCEPROP 2 LAST CDS_LIB mstr_standard
J 0
(-2425 4600);
DISPLAY 0.723404 (-2425 4600);
PAINT MONO (-2425 4600);
DISPLAY INVISIBLE (-2425 4600);
FORCEPROP 1 LAST OFFPAGE TRUE
J 0
(-2100 4475);
DISPLAY 0.723404 (-2100 4475);
PAINT GREEN (-2100 4475);
DISPLAY INVISIBLE (-2100 4475);
FORCEPROP 1 LAST COMMENT_BODY TRUE
J 0
(-2470 4505);
DISPLAY 0.872340 (-2470 4505);
PAINT GREEN (-2470 4505);
DISPLAY INVISIBLE (-2470 4505);
FORCEPROP 2 LAST PATH I195
J 0
(-2225 4650);
DISPLAY 0.680851 (-2225 4650);
DISPLAY INVISIBLE (-2225 4650);
FORCEADD OFFPAGE..2
(-2425 3600);
FORCEPROP 2 LAST $XR0 37 
J 0
(-2236 3600);
DISPLAY 0.638298 (-2236 3600);
PAINT MONO (-2236 3600);
FORCEPROP 2 LAST CDS_LIB mstr_standard
J 0
(-2425 3600);
DISPLAY 0.723404 (-2425 3600);
PAINT MONO (-2425 3600);
DISPLAY INVISIBLE (-2425 3600);
FORCEPROP 1 LAST OFFPAGE TRUE
J 0
(-2100 3475);
DISPLAY 0.723404 (-2100 3475);
PAINT GREEN (-2100 3475);
DISPLAY INVISIBLE (-2100 3475);
FORCEPROP 1 LAST COMMENT_BODY TRUE
J 0
(-2470 3505);
DISPLAY 0.872340 (-2470 3505);
PAINT GREEN (-2470 3505);
DISPLAY INVISIBLE (-2470 3505);
FORCEPROP 2 LAST PATH I196
J 0
(-2225 3650);
DISPLAY 0.680851 (-2225 3650);
DISPLAY INVISIBLE (-2225 3650);
FORCEADD OFFPAGE..2
(-2425 3550);
FORCEPROP 2 LAST $XR0 37 
J 0
(-2236 3550);
DISPLAY 0.638298 (-2236 3550);
PAINT MONO (-2236 3550);
FORCEPROP 2 LAST CDS_LIB mstr_standard
J 0
(-2425 3550);
DISPLAY 0.723404 (-2425 3550);
PAINT MONO (-2425 3550);
DISPLAY INVISIBLE (-2425 3550);
FORCEPROP 1 LAST OFFPAGE TRUE
J 0
(-2100 3425);
DISPLAY 0.723404 (-2100 3425);
PAINT GREEN (-2100 3425);
DISPLAY INVISIBLE (-2100 3425);
FORCEPROP 1 LAST COMMENT_BODY TRUE
J 0
(-2470 3455);
DISPLAY 0.872340 (-2470 3455);
PAINT GREEN (-2470 3455);
DISPLAY INVISIBLE (-2470 3455);
FORCEPROP 2 LAST PATH I197
J 0
(-2225 3600);
DISPLAY 0.680851 (-2225 3600);
DISPLAY INVISIBLE (-2225 3600);
FORCEADD TAP..1
(-3025 4550);
FORCEPROP 3 LASTPIN (-3075 4550) SIG_NAME M_A_CPU1_SA_DQS_DN<9>
J 0
(-3065 4560);
DISPLAY 0.659574 (-3065 4560);
PAINT MONO (-3065 4560);
DISPLAY INVISIBLE (-3065 4560);
FORCEPROP 1 LASTPIN (-3075 4550) BN 9
J 0
(-3087 4558);
DISPLAY 0.489362 (-3087 4558);
PAINT GREEN (-3087 4558);
FORCEPROP 2 LAST CDS_LIB mstr_standard
J 0
(-3025 4550);
DISPLAY 0.723404 (-3025 4550);
PAINT MONO (-3025 4550);
DISPLAY INVISIBLE (-3025 4550);
FORCEPROP 1 LAST BODY_TYPE PLUMBING
J 0
(-3025 4600);
DISPLAY 0.872340 (-3025 4600);
PAINT GREEN (-3025 4600);
DISPLAY INVISIBLE (-3025 4600);
FORCEPROP 1 LAST HDL_TAP TRUE
J 0
(-2700 4425);
DISPLAY 0.872340 (-2700 4425);
DISPLAY INVISIBLE (-2700 4425);
FORCEPROP 1 LAST PATH I198
J 0
(-3027 4550);
DISPLAY 0.872340 (-3027 4550);
PAINT GREEN (-3027 4550);
DISPLAY INVISIBLE (-3027 4550);
FORCEADD TAP..1
(-3025 4450);
FORCEPROP 3 LASTPIN (-3075 4450) SIG_NAME M_A_CPU1_SA_DQS_DN<8>
J 0
(-3065 4460);
DISPLAY 0.659574 (-3065 4460);
PAINT MONO (-3065 4460);
DISPLAY INVISIBLE (-3065 4460);
FORCEPROP 1 LASTPIN (-3075 4450) BN 8
J 0
(-3087 4458);
DISPLAY 0.489362 (-3087 4458);
PAINT GREEN (-3087 4458);
FORCEPROP 2 LAST CDS_LIB mstr_standard
J 0
(-3025 4450);
DISPLAY 0.723404 (-3025 4450);
PAINT MONO (-3025 4450);
DISPLAY INVISIBLE (-3025 4450);
FORCEPROP 1 LAST BODY_TYPE PLUMBING
J 0
(-3025 4500);
DISPLAY 0.872340 (-3025 4500);
PAINT GREEN (-3025 4500);
DISPLAY INVISIBLE (-3025 4500);
FORCEPROP 1 LAST HDL_TAP TRUE
J 0
(-2700 4325);
DISPLAY 0.872340 (-2700 4325);
DISPLAY INVISIBLE (-2700 4325);
FORCEPROP 1 LAST PATH I199
J 0
(-3027 4450);
DISPLAY 0.872340 (-3027 4450);
PAINT GREEN (-3027 4450);
DISPLAY INVISIBLE (-3027 4450);
FORCEADD OFFPAGE..5
(-8050 2075);
FORCEPROP 2 LAST $XR0 37 
J 0
(-8304 2075);
DISPLAY 0.638298 (-8304 2075);
PAINT MONO (-8304 2075);
FORCEPROP 2 LAST CDS_LIB mstr_standard
J 0
(-8050 2075);
DISPLAY 0.808511 (-8050 2075);
DISPLAY INVISIBLE (-8050 2075);
FORCEPROP 1 LAST OFFPAGE TRUE
J 0
(-7725 1950);
DISPLAY 0.872340 (-7725 1950);
PAINT GREEN (-7725 1950);
DISPLAY INVISIBLE (-7725 1950);
FORCEPROP 1 LAST COMMENT_BODY TRUE
J 0
(-7950 2000);
DISPLAY 0.872340 (-7950 2000);
PAINT GREEN (-7950 2000);
DISPLAY INVISIBLE (-7950 2000);
FORCEPROP 2 LAST PATH I2
J 0
(-8250 2125);
DISPLAY 1.021277 (-8250 2125);
DISPLAY INVISIBLE (-8250 2125);
FORCEADD OFFPAGE..1
(-8050 5125);
FORCEPROP 2 LAST $XR0 37 
J 0
(-8271 5125);
DISPLAY 0.638298 (-8271 5125);
PAINT MONO (-8271 5125);
FORCEPROP 2 LAST CDS_LIB mstr_standard
J 0
(-8050 5125);
DISPLAY 0.723404 (-8050 5125);
PAINT MONO (-8050 5125);
DISPLAY INVISIBLE (-8050 5125);
FORCEPROP 1 LAST OFFPAGE TRUE
J 0
(-7725 5000);
DISPLAY 0.872340 (-7725 5000);
PAINT GREEN (-7725 5000);
DISPLAY INVISIBLE (-7725 5000);
FORCEPROP 1 LAST COMMENT_BODY TRUE
J 0
(-7925 5025);
DISPLAY 0.872340 (-7925 5025);
PAINT GREEN (-7925 5025);
DISPLAY INVISIBLE (-7925 5025);
FORCEPROP 2 LAST PATH I20
J 0
(-8300 5175);
DISPLAY 1.021277 (-8300 5175);
DISPLAY INVISIBLE (-8300 5175);
FORCEADD TAP..1
(-3025 4350);
FORCEPROP 3 LASTPIN (-3075 4350) SIG_NAME M_A_CPU1_SA_DQS_DN<7>
J 0
(-3065 4360);
DISPLAY 0.659574 (-3065 4360);
PAINT MONO (-3065 4360);
DISPLAY INVISIBLE (-3065 4360);
FORCEPROP 1 LASTPIN (-3075 4350) BN 7
J 0
(-3087 4358);
DISPLAY 0.489362 (-3087 4358);
PAINT GREEN (-3087 4358);
FORCEPROP 2 LAST CDS_LIB mstr_standard
J 0
(-3025 4350);
DISPLAY 0.723404 (-3025 4350);
PAINT MONO (-3025 4350);
DISPLAY INVISIBLE (-3025 4350);
FORCEPROP 1 LAST BODY_TYPE PLUMBING
J 0
(-3025 4400);
DISPLAY 0.872340 (-3025 4400);
PAINT GREEN (-3025 4400);
DISPLAY INVISIBLE (-3025 4400);
FORCEPROP 1 LAST HDL_TAP TRUE
J 0
(-2700 4225);
DISPLAY 0.872340 (-2700 4225);
DISPLAY INVISIBLE (-2700 4225);
FORCEPROP 1 LAST PATH I200
J 0
(-3027 4350);
DISPLAY 0.872340 (-3027 4350);
PAINT GREEN (-3027 4350);
DISPLAY INVISIBLE (-3027 4350);
FORCEADD TAP..1
(-3225 4600);
FORCEPROP 3 LASTPIN (-3275 4600) SIG_NAME M_A_CPU1_SA_DQS_DP<9>
J 0
(-3265 4610);
DISPLAY 0.659574 (-3265 4610);
PAINT MONO (-3265 4610);
DISPLAY INVISIBLE (-3265 4610);
FORCEPROP 1 LASTPIN (-3275 4600) BN 9
J 0
(-3287 4608);
DISPLAY 0.489362 (-3287 4608);
PAINT GREEN (-3287 4608);
FORCEPROP 2 LAST CDS_LIB mstr_standard
J 0
(-3225 4600);
DISPLAY 0.723404 (-3225 4600);
PAINT MONO (-3225 4600);
DISPLAY INVISIBLE (-3225 4600);
FORCEPROP 1 LAST BODY_TYPE PLUMBING
J 0
(-3225 4650);
DISPLAY 0.872340 (-3225 4650);
PAINT GREEN (-3225 4650);
DISPLAY INVISIBLE (-3225 4650);
FORCEPROP 1 LAST HDL_TAP TRUE
J 0
(-2900 4475);
DISPLAY 0.872340 (-2900 4475);
DISPLAY INVISIBLE (-2900 4475);
FORCEPROP 1 LAST PATH I201
J 0
(-3227 4600);
DISPLAY 0.872340 (-3227 4600);
PAINT GREEN (-3227 4600);
DISPLAY INVISIBLE (-3227 4600);
FORCEADD TAP..1
(-3225 4500);
FORCEPROP 3 LASTPIN (-3275 4500) SIG_NAME M_A_CPU1_SA_DQS_DP<8>
J 0
(-3265 4510);
DISPLAY 0.659574 (-3265 4510);
PAINT MONO (-3265 4510);
DISPLAY INVISIBLE (-3265 4510);
FORCEPROP 1 LASTPIN (-3275 4500) BN 8
J 0
(-3287 4508);
DISPLAY 0.489362 (-3287 4508);
PAINT GREEN (-3287 4508);
FORCEPROP 2 LAST CDS_LIB mstr_standard
J 0
(-3225 4500);
DISPLAY 0.723404 (-3225 4500);
PAINT MONO (-3225 4500);
DISPLAY INVISIBLE (-3225 4500);
FORCEPROP 1 LAST BODY_TYPE PLUMBING
J 0
(-3225 4550);
DISPLAY 0.872340 (-3225 4550);
PAINT GREEN (-3225 4550);
DISPLAY INVISIBLE (-3225 4550);
FORCEPROP 1 LAST HDL_TAP TRUE
J 0
(-2900 4375);
DISPLAY 0.872340 (-2900 4375);
DISPLAY INVISIBLE (-2900 4375);
FORCEPROP 1 LAST PATH I202
J 0
(-3227 4500);
DISPLAY 0.872340 (-3227 4500);
PAINT GREEN (-3227 4500);
DISPLAY INVISIBLE (-3227 4500);
FORCEADD TAP..1
(-3225 4400);
FORCEPROP 3 LASTPIN (-3275 4400) SIG_NAME M_A_CPU1_SA_DQS_DP<7>
J 0
(-3265 4410);
DISPLAY 0.659574 (-3265 4410);
PAINT MONO (-3265 4410);
DISPLAY INVISIBLE (-3265 4410);
FORCEPROP 1 LASTPIN (-3275 4400) BN 7
J 0
(-3287 4408);
DISPLAY 0.489362 (-3287 4408);
PAINT GREEN (-3287 4408);
FORCEPROP 2 LAST CDS_LIB mstr_standard
J 0
(-3225 4400);
DISPLAY 0.723404 (-3225 4400);
PAINT MONO (-3225 4400);
DISPLAY INVISIBLE (-3225 4400);
FORCEPROP 1 LAST BODY_TYPE PLUMBING
J 0
(-3225 4450);
DISPLAY 0.872340 (-3225 4450);
PAINT GREEN (-3225 4450);
DISPLAY INVISIBLE (-3225 4450);
FORCEPROP 1 LAST HDL_TAP TRUE
J 0
(-2900 4275);
DISPLAY 0.872340 (-2900 4275);
DISPLAY INVISIBLE (-2900 4275);
FORCEPROP 1 LAST PATH I203
J 0
(-3227 4400);
DISPLAY 0.872340 (-3227 4400);
PAINT GREEN (-3227 4400);
DISPLAY INVISIBLE (-3227 4400);
FORCEADD TAP..1
(-3025 4250);
FORCEPROP 3 LASTPIN (-3075 4250) SIG_NAME M_A_CPU1_SA_DQS_DN<6>
J 0
(-3065 4260);
DISPLAY 0.659574 (-3065 4260);
PAINT MONO (-3065 4260);
DISPLAY INVISIBLE (-3065 4260);
FORCEPROP 1 LASTPIN (-3075 4250) BN 6
J 0
(-3087 4258);
DISPLAY 0.489362 (-3087 4258);
PAINT GREEN (-3087 4258);
FORCEPROP 2 LAST CDS_LIB mstr_standard
J 0
(-3025 4250);
DISPLAY 0.723404 (-3025 4250);
PAINT MONO (-3025 4250);
DISPLAY INVISIBLE (-3025 4250);
FORCEPROP 1 LAST BODY_TYPE PLUMBING
J 0
(-3025 4300);
DISPLAY 0.872340 (-3025 4300);
PAINT GREEN (-3025 4300);
DISPLAY INVISIBLE (-3025 4300);
FORCEPROP 1 LAST HDL_TAP TRUE
J 0
(-2700 4125);
DISPLAY 0.872340 (-2700 4125);
DISPLAY INVISIBLE (-2700 4125);
FORCEPROP 1 LAST PATH I204
J 0
(-3027 4250);
DISPLAY 0.872340 (-3027 4250);
PAINT GREEN (-3027 4250);
DISPLAY INVISIBLE (-3027 4250);
FORCEADD TAP..1
(-3025 4150);
FORCEPROP 3 LASTPIN (-3075 4150) SIG_NAME M_A_CPU1_SA_DQS_DN<5>
J 0
(-3065 4160);
DISPLAY 0.659574 (-3065 4160);
PAINT MONO (-3065 4160);
DISPLAY INVISIBLE (-3065 4160);
FORCEPROP 1 LASTPIN (-3075 4150) BN 5
J 0
(-3087 4158);
DISPLAY 0.489362 (-3087 4158);
PAINT GREEN (-3087 4158);
FORCEPROP 2 LAST CDS_LIB mstr_standard
J 0
(-3025 4150);
DISPLAY 0.723404 (-3025 4150);
PAINT MONO (-3025 4150);
DISPLAY INVISIBLE (-3025 4150);
FORCEPROP 1 LAST BODY_TYPE PLUMBING
J 0
(-3025 4200);
DISPLAY 0.872340 (-3025 4200);
PAINT GREEN (-3025 4200);
DISPLAY INVISIBLE (-3025 4200);
FORCEPROP 1 LAST HDL_TAP TRUE
J 0
(-2700 4025);
DISPLAY 0.872340 (-2700 4025);
DISPLAY INVISIBLE (-2700 4025);
FORCEPROP 1 LAST PATH I205
J 0
(-3027 4150);
DISPLAY 0.872340 (-3027 4150);
PAINT GREEN (-3027 4150);
DISPLAY INVISIBLE (-3027 4150);
FORCEADD TAP..1
(-3025 3950);
FORCEPROP 3 LASTPIN (-3075 3950) SIG_NAME M_A_CPU1_SA_DQS_DN<3>
J 0
(-3065 3960);
DISPLAY 0.659574 (-3065 3960);
PAINT MONO (-3065 3960);
DISPLAY INVISIBLE (-3065 3960);
FORCEPROP 1 LASTPIN (-3075 3950) BN 3
J 0
(-3087 3958);
DISPLAY 0.489362 (-3087 3958);
PAINT GREEN (-3087 3958);
FORCEPROP 2 LAST CDS_LIB mstr_standard
J 0
(-3025 3950);
DISPLAY 0.723404 (-3025 3950);
PAINT MONO (-3025 3950);
DISPLAY INVISIBLE (-3025 3950);
FORCEPROP 1 LAST BODY_TYPE PLUMBING
J 0
(-3025 4000);
DISPLAY 0.872340 (-3025 4000);
PAINT GREEN (-3025 4000);
DISPLAY INVISIBLE (-3025 4000);
FORCEPROP 1 LAST HDL_TAP TRUE
J 0
(-2700 3825);
DISPLAY 0.872340 (-2700 3825);
DISPLAY INVISIBLE (-2700 3825);
FORCEPROP 1 LAST PATH I206
J 0
(-3027 3950);
DISPLAY 0.872340 (-3027 3950);
PAINT GREEN (-3027 3950);
DISPLAY INVISIBLE (-3027 3950);
FORCEADD TAP..1
(-3025 4050);
FORCEPROP 3 LASTPIN (-3075 4050) SIG_NAME M_A_CPU1_SA_DQS_DN<4>
J 0
(-3065 4060);
DISPLAY 0.659574 (-3065 4060);
PAINT MONO (-3065 4060);
DISPLAY INVISIBLE (-3065 4060);
FORCEPROP 1 LASTPIN (-3075 4050) BN 4
J 0
(-3087 4058);
DISPLAY 0.489362 (-3087 4058);
PAINT GREEN (-3087 4058);
FORCEPROP 2 LAST CDS_LIB mstr_standard
J 0
(-3025 4050);
DISPLAY 0.723404 (-3025 4050);
PAINT MONO (-3025 4050);
DISPLAY INVISIBLE (-3025 4050);
FORCEPROP 1 LAST BODY_TYPE PLUMBING
J 0
(-3025 4100);
DISPLAY 0.872340 (-3025 4100);
PAINT GREEN (-3025 4100);
DISPLAY INVISIBLE (-3025 4100);
FORCEPROP 1 LAST HDL_TAP TRUE
J 0
(-2700 3925);
DISPLAY 0.872340 (-2700 3925);
DISPLAY INVISIBLE (-2700 3925);
FORCEPROP 1 LAST PATH I207
J 0
(-3027 4050);
DISPLAY 0.872340 (-3027 4050);
PAINT GREEN (-3027 4050);
DISPLAY INVISIBLE (-3027 4050);
FORCEADD TAP..1
(-3025 3850);
FORCEPROP 3 LASTPIN (-3075 3850) SIG_NAME M_A_CPU1_SA_DQS_DN<2>
J 0
(-3065 3860);
DISPLAY 0.659574 (-3065 3860);
PAINT MONO (-3065 3860);
DISPLAY INVISIBLE (-3065 3860);
FORCEPROP 1 LASTPIN (-3075 3850) BN 2
J 0
(-3087 3858);
DISPLAY 0.489362 (-3087 3858);
PAINT GREEN (-3087 3858);
FORCEPROP 2 LAST CDS_LIB mstr_standard
J 0
(-3025 3850);
DISPLAY 0.723404 (-3025 3850);
PAINT MONO (-3025 3850);
DISPLAY INVISIBLE (-3025 3850);
FORCEPROP 1 LAST BODY_TYPE PLUMBING
J 0
(-3025 3900);
DISPLAY 0.872340 (-3025 3900);
PAINT GREEN (-3025 3900);
DISPLAY INVISIBLE (-3025 3900);
FORCEPROP 1 LAST HDL_TAP TRUE
J 0
(-2700 3725);
DISPLAY 0.872340 (-2700 3725);
DISPLAY INVISIBLE (-2700 3725);
FORCEPROP 1 LAST PATH I208
J 0
(-3027 3850);
DISPLAY 0.872340 (-3027 3850);
PAINT GREEN (-3027 3850);
DISPLAY INVISIBLE (-3027 3850);
FORCEADD TAP..1
(-3225 4100);
FORCEPROP 3 LASTPIN (-3275 4100) SIG_NAME M_A_CPU1_SA_DQS_DP<4>
J 0
(-3265 4110);
DISPLAY 0.659574 (-3265 4110);
PAINT MONO (-3265 4110);
DISPLAY INVISIBLE (-3265 4110);
FORCEPROP 1 LASTPIN (-3275 4100) BN 4
J 0
(-3287 4108);
DISPLAY 0.489362 (-3287 4108);
PAINT GREEN (-3287 4108);
FORCEPROP 2 LAST CDS_LIB mstr_standard
J 0
(-3225 4100);
DISPLAY 0.723404 (-3225 4100);
PAINT MONO (-3225 4100);
DISPLAY INVISIBLE (-3225 4100);
FORCEPROP 1 LAST BODY_TYPE PLUMBING
J 0
(-3225 4150);
DISPLAY 0.872340 (-3225 4150);
PAINT GREEN (-3225 4150);
DISPLAY INVISIBLE (-3225 4150);
FORCEPROP 1 LAST HDL_TAP TRUE
J 0
(-2900 3975);
DISPLAY 0.872340 (-2900 3975);
DISPLAY INVISIBLE (-2900 3975);
FORCEPROP 1 LAST PATH I209
J 0
(-3227 4100);
DISPLAY 0.872340 (-3227 4100);
PAINT GREEN (-3227 4100);
DISPLAY INVISIBLE (-3227 4100);
FORCEADD OFFPAGE..1
(-8050 5525);
FORCEPROP 2 LAST $XR0 37 
J 0
(-8271 5525);
DISPLAY 0.638298 (-8271 5525);
PAINT MONO (-8271 5525);
FORCEPROP 2 LAST CDS_LIB mstr_standard
J 0
(-8050 5525);
DISPLAY 0.723404 (-8050 5525);
PAINT MONO (-8050 5525);
DISPLAY INVISIBLE (-8050 5525);
FORCEPROP 1 LAST OFFPAGE TRUE
J 0
(-7725 5400);
DISPLAY 0.872340 (-7725 5400);
PAINT GREEN (-7725 5400);
DISPLAY INVISIBLE (-7725 5400);
FORCEPROP 1 LAST COMMENT_BODY TRUE
J 0
(-7925 5425);
DISPLAY 0.872340 (-7925 5425);
PAINT GREEN (-7925 5425);
DISPLAY INVISIBLE (-7925 5425);
FORCEPROP 2 LAST PATH I21
J 0
(-8300 5575);
DISPLAY 1.021277 (-8300 5575);
DISPLAY INVISIBLE (-8300 5575);
FORCEADD TAP..1
(-3225 4200);
FORCEPROP 3 LASTPIN (-3275 4200) SIG_NAME M_A_CPU1_SA_DQS_DP<5>
J 0
(-3265 4210);
DISPLAY 0.659574 (-3265 4210);
PAINT MONO (-3265 4210);
DISPLAY INVISIBLE (-3265 4210);
FORCEPROP 1 LASTPIN (-3275 4200) BN 5
J 0
(-3287 4208);
DISPLAY 0.489362 (-3287 4208);
PAINT GREEN (-3287 4208);
FORCEPROP 2 LAST CDS_LIB mstr_standard
J 0
(-3225 4200);
DISPLAY 0.723404 (-3225 4200);
PAINT MONO (-3225 4200);
DISPLAY INVISIBLE (-3225 4200);
FORCEPROP 1 LAST BODY_TYPE PLUMBING
J 0
(-3225 4250);
DISPLAY 0.872340 (-3225 4250);
PAINT GREEN (-3225 4250);
DISPLAY INVISIBLE (-3225 4250);
FORCEPROP 1 LAST HDL_TAP TRUE
J 0
(-2900 4075);
DISPLAY 0.872340 (-2900 4075);
DISPLAY INVISIBLE (-2900 4075);
FORCEPROP 1 LAST PATH I210
J 0
(-3227 4200);
DISPLAY 0.872340 (-3227 4200);
PAINT GREEN (-3227 4200);
DISPLAY INVISIBLE (-3227 4200);
FORCEADD TAP..1
(-3225 4300);
FORCEPROP 3 LASTPIN (-3275 4300) SIG_NAME M_A_CPU1_SA_DQS_DP<6>
J 0
(-3265 4310);
DISPLAY 0.659574 (-3265 4310);
PAINT MONO (-3265 4310);
DISPLAY INVISIBLE (-3265 4310);
FORCEPROP 1 LASTPIN (-3275 4300) BN 6
J 0
(-3287 4308);
DISPLAY 0.489362 (-3287 4308);
PAINT GREEN (-3287 4308);
FORCEPROP 2 LAST CDS_LIB mstr_standard
J 0
(-3225 4300);
DISPLAY 0.723404 (-3225 4300);
PAINT MONO (-3225 4300);
DISPLAY INVISIBLE (-3225 4300);
FORCEPROP 1 LAST BODY_TYPE PLUMBING
J 0
(-3225 4350);
DISPLAY 0.872340 (-3225 4350);
PAINT GREEN (-3225 4350);
DISPLAY INVISIBLE (-3225 4350);
FORCEPROP 1 LAST HDL_TAP TRUE
J 0
(-2900 4175);
DISPLAY 0.872340 (-2900 4175);
DISPLAY INVISIBLE (-2900 4175);
FORCEPROP 1 LAST PATH I211
J 0
(-3227 4300);
DISPLAY 0.872340 (-3227 4300);
PAINT GREEN (-3227 4300);
DISPLAY INVISIBLE (-3227 4300);
FORCEADD TAP..1
(-3225 4000);
FORCEPROP 3 LASTPIN (-3275 4000) SIG_NAME M_A_CPU1_SA_DQS_DP<3>
J 0
(-3265 4010);
DISPLAY 0.659574 (-3265 4010);
PAINT MONO (-3265 4010);
DISPLAY INVISIBLE (-3265 4010);
FORCEPROP 1 LASTPIN (-3275 4000) BN 3
J 0
(-3287 4008);
DISPLAY 0.489362 (-3287 4008);
PAINT GREEN (-3287 4008);
FORCEPROP 2 LAST CDS_LIB mstr_standard
J 0
(-3225 4000);
DISPLAY 0.723404 (-3225 4000);
PAINT MONO (-3225 4000);
DISPLAY INVISIBLE (-3225 4000);
FORCEPROP 1 LAST BODY_TYPE PLUMBING
J 0
(-3225 4050);
DISPLAY 0.872340 (-3225 4050);
PAINT GREEN (-3225 4050);
DISPLAY INVISIBLE (-3225 4050);
FORCEPROP 1 LAST HDL_TAP TRUE
J 0
(-2900 3875);
DISPLAY 0.872340 (-2900 3875);
DISPLAY INVISIBLE (-2900 3875);
FORCEPROP 1 LAST PATH I212
J 0
(-3227 4000);
DISPLAY 0.872340 (-3227 4000);
PAINT GREEN (-3227 4000);
DISPLAY INVISIBLE (-3227 4000);
FORCEADD TAP..1
(-3225 3900);
FORCEPROP 3 LASTPIN (-3275 3900) SIG_NAME M_A_CPU1_SA_DQS_DP<2>
J 0
(-3265 3910);
DISPLAY 0.659574 (-3265 3910);
PAINT MONO (-3265 3910);
DISPLAY INVISIBLE (-3265 3910);
FORCEPROP 1 LASTPIN (-3275 3900) BN 2
J 0
(-3287 3908);
DISPLAY 0.489362 (-3287 3908);
PAINT GREEN (-3287 3908);
FORCEPROP 2 LAST CDS_LIB mstr_standard
J 0
(-3225 3900);
DISPLAY 0.723404 (-3225 3900);
PAINT MONO (-3225 3900);
DISPLAY INVISIBLE (-3225 3900);
FORCEPROP 1 LAST BODY_TYPE PLUMBING
J 0
(-3225 3950);
DISPLAY 0.872340 (-3225 3950);
PAINT GREEN (-3225 3950);
DISPLAY INVISIBLE (-3225 3950);
FORCEPROP 1 LAST HDL_TAP TRUE
J 0
(-2900 3775);
DISPLAY 0.872340 (-2900 3775);
DISPLAY INVISIBLE (-2900 3775);
FORCEPROP 1 LAST PATH I213
J 0
(-3227 3900);
DISPLAY 0.872340 (-3227 3900);
PAINT GREEN (-3227 3900);
DISPLAY INVISIBLE (-3227 3900);
FORCEADD TAP..1
(-3025 3750);
FORCEPROP 3 LASTPIN (-3075 3750) SIG_NAME M_A_CPU1_SA_DQS_DN<1>
J 0
(-3065 3760);
DISPLAY 0.659574 (-3065 3760);
PAINT MONO (-3065 3760);
DISPLAY INVISIBLE (-3065 3760);
FORCEPROP 1 LASTPIN (-3075 3750) BN 1
J 0
(-3087 3758);
DISPLAY 0.489362 (-3087 3758);
PAINT GREEN (-3087 3758);
FORCEPROP 2 LAST CDS_LIB mstr_standard
J 0
(-3025 3750);
DISPLAY 0.723404 (-3025 3750);
PAINT MONO (-3025 3750);
DISPLAY INVISIBLE (-3025 3750);
FORCEPROP 1 LAST BODY_TYPE PLUMBING
J 0
(-3025 3800);
DISPLAY 0.872340 (-3025 3800);
PAINT GREEN (-3025 3800);
DISPLAY INVISIBLE (-3025 3800);
FORCEPROP 1 LAST HDL_TAP TRUE
J 0
(-2700 3625);
DISPLAY 0.872340 (-2700 3625);
DISPLAY INVISIBLE (-2700 3625);
FORCEPROP 1 LAST PATH I214
J 0
(-3027 3750);
DISPLAY 0.872340 (-3027 3750);
PAINT GREEN (-3027 3750);
DISPLAY INVISIBLE (-3027 3750);
FORCEADD TAP..1
(-3025 3650);
FORCEPROP 3 LASTPIN (-3075 3650) SIG_NAME M_A_CPU1_SA_DQS_DN<0>
J 0
(-3065 3660);
DISPLAY 0.659574 (-3065 3660);
PAINT MONO (-3065 3660);
DISPLAY INVISIBLE (-3065 3660);
FORCEPROP 1 LASTPIN (-3075 3650) BN 0
J 0
(-3087 3658);
DISPLAY 0.489362 (-3087 3658);
PAINT GREEN (-3087 3658);
FORCEPROP 2 LAST CDS_LIB mstr_standard
J 0
(-3025 3650);
DISPLAY 0.723404 (-3025 3650);
PAINT MONO (-3025 3650);
DISPLAY INVISIBLE (-3025 3650);
FORCEPROP 1 LAST BODY_TYPE PLUMBING
J 0
(-3025 3700);
DISPLAY 0.872340 (-3025 3700);
PAINT GREEN (-3025 3700);
DISPLAY INVISIBLE (-3025 3700);
FORCEPROP 1 LAST HDL_TAP TRUE
J 0
(-2700 3525);
DISPLAY 0.872340 (-2700 3525);
DISPLAY INVISIBLE (-2700 3525);
FORCEPROP 1 LAST PATH I215
J 0
(-3027 3650);
DISPLAY 0.872340 (-3027 3650);
PAINT GREEN (-3027 3650);
DISPLAY INVISIBLE (-3027 3650);
FORCEADD TAP..1
(-3025 3500);
FORCEPROP 3 LASTPIN (-3075 3500) SIG_NAME M_A_CPU1_SB_DQS_DN<9>
J 0
(-3065 3510);
DISPLAY 0.659574 (-3065 3510);
PAINT MONO (-3065 3510);
DISPLAY INVISIBLE (-3065 3510);
FORCEPROP 1 LASTPIN (-3075 3500) BN 9
J 0
(-3087 3508);
DISPLAY 0.489362 (-3087 3508);
PAINT GREEN (-3087 3508);
FORCEPROP 2 LAST CDS_LIB mstr_standard
J 0
(-3025 3500);
DISPLAY 0.723404 (-3025 3500);
PAINT MONO (-3025 3500);
DISPLAY INVISIBLE (-3025 3500);
FORCEPROP 1 LAST BODY_TYPE PLUMBING
J 0
(-3025 3550);
DISPLAY 0.872340 (-3025 3550);
PAINT GREEN (-3025 3550);
DISPLAY INVISIBLE (-3025 3550);
FORCEPROP 1 LAST HDL_TAP TRUE
J 0
(-2700 3375);
DISPLAY 0.872340 (-2700 3375);
DISPLAY INVISIBLE (-2700 3375);
FORCEPROP 1 LAST PATH I216
J 0
(-3027 3500);
DISPLAY 0.872340 (-3027 3500);
PAINT GREEN (-3027 3500);
DISPLAY INVISIBLE (-3027 3500);
FORCEADD TAP..1
(-3025 3400);
FORCEPROP 3 LASTPIN (-3075 3400) SIG_NAME M_A_CPU1_SB_DQS_DN<8>
J 0
(-3065 3410);
DISPLAY 0.659574 (-3065 3410);
PAINT MONO (-3065 3410);
DISPLAY INVISIBLE (-3065 3410);
FORCEPROP 1 LASTPIN (-3075 3400) BN 8
J 0
(-3087 3408);
DISPLAY 0.489362 (-3087 3408);
PAINT GREEN (-3087 3408);
FORCEPROP 2 LAST CDS_LIB mstr_standard
J 0
(-3025 3400);
DISPLAY 0.723404 (-3025 3400);
PAINT MONO (-3025 3400);
DISPLAY INVISIBLE (-3025 3400);
FORCEPROP 1 LAST BODY_TYPE PLUMBING
J 0
(-3025 3450);
DISPLAY 0.872340 (-3025 3450);
PAINT GREEN (-3025 3450);
DISPLAY INVISIBLE (-3025 3450);
FORCEPROP 1 LAST HDL_TAP TRUE
J 0
(-2700 3275);
DISPLAY 0.872340 (-2700 3275);
DISPLAY INVISIBLE (-2700 3275);
FORCEPROP 1 LAST PATH I217
J 0
(-3027 3400);
DISPLAY 0.872340 (-3027 3400);
PAINT GREEN (-3027 3400);
DISPLAY INVISIBLE (-3027 3400);
FORCEADD TAP..1
(-3025 3300);
FORCEPROP 3 LASTPIN (-3075 3300) SIG_NAME M_A_CPU1_SB_DQS_DN<7>
J 0
(-3065 3310);
DISPLAY 0.659574 (-3065 3310);
PAINT MONO (-3065 3310);
DISPLAY INVISIBLE (-3065 3310);
FORCEPROP 1 LASTPIN (-3075 3300) BN 7
J 0
(-3087 3308);
DISPLAY 0.489362 (-3087 3308);
PAINT GREEN (-3087 3308);
FORCEPROP 2 LAST CDS_LIB mstr_standard
J 0
(-3025 3300);
DISPLAY 0.723404 (-3025 3300);
PAINT MONO (-3025 3300);
DISPLAY INVISIBLE (-3025 3300);
FORCEPROP 1 LAST BODY_TYPE PLUMBING
J 0
(-3025 3350);
DISPLAY 0.872340 (-3025 3350);
PAINT GREEN (-3025 3350);
DISPLAY INVISIBLE (-3025 3350);
FORCEPROP 1 LAST HDL_TAP TRUE
J 0
(-2700 3175);
DISPLAY 0.872340 (-2700 3175);
DISPLAY INVISIBLE (-2700 3175);
FORCEPROP 1 LAST PATH I218
J 0
(-3027 3300);
DISPLAY 0.872340 (-3027 3300);
PAINT GREEN (-3027 3300);
DISPLAY INVISIBLE (-3027 3300);
FORCEADD TAP..1
(-3225 3700);
FORCEPROP 3 LASTPIN (-3275 3700) SIG_NAME M_A_CPU1_SA_DQS_DP<0>
J 0
(-3265 3710);
DISPLAY 0.659574 (-3265 3710);
PAINT MONO (-3265 3710);
DISPLAY INVISIBLE (-3265 3710);
FORCEPROP 1 LASTPIN (-3275 3700) BN 0
J 0
(-3287 3708);
DISPLAY 0.489362 (-3287 3708);
PAINT GREEN (-3287 3708);
FORCEPROP 2 LAST CDS_LIB mstr_standard
J 0
(-3225 3700);
DISPLAY 0.723404 (-3225 3700);
PAINT MONO (-3225 3700);
DISPLAY INVISIBLE (-3225 3700);
FORCEPROP 1 LAST BODY_TYPE PLUMBING
J 0
(-3225 3750);
DISPLAY 0.872340 (-3225 3750);
PAINT GREEN (-3225 3750);
DISPLAY INVISIBLE (-3225 3750);
FORCEPROP 1 LAST HDL_TAP TRUE
J 0
(-2900 3575);
DISPLAY 0.872340 (-2900 3575);
DISPLAY INVISIBLE (-2900 3575);
FORCEPROP 1 LAST PATH I219
J 0
(-3227 3700);
DISPLAY 0.872340 (-3227 3700);
PAINT GREEN (-3227 3700);
DISPLAY INVISIBLE (-3227 3700);
FORCEADD SCONN288_DDR506112002KQ..1
(-6600 3725);
FORCEPROP 1 LAST LOCATION J24
J 0
(-7050 5800);
DISPLAY 0.468085 (-7050 5800);
PAINT SKYBLUE (-7050 5800);
FORCEPROP 0 LAST $SEC 1
J 0
(-7050 5950);
DISPLAY 0.680851 (-7050 5950);
PAINT MONO (-7050 5950);
DISPLAY INVISIBLE (-7050 5950);
FORCEPROP 0 LAST CDS_SEC 1
J 0
(-7050 5950);
DISPLAY 0.680851 (-7050 5950);
DISPLAY INVISIBLE (-7050 5950);
FORCEPROP 0 LASTPIN (-7200 3125) $PN 62
J 2
(-7210 3135);
DISPLAY 0.680851 (-7210 3135);
PAINT MONO (-7210 3135);
FORCEPROP 0 LASTPIN (-7200 5175) $PN 66
J 2
(-7210 5185);
DISPLAY 0.680851 (-7210 5185);
PAINT MONO (-7210 5185);
FORCEPROP 0 LASTPIN (-7200 4775) $PN 76
J 2
(-7210 4785);
DISPLAY 0.680851 (-7210 4785);
PAINT MONO (-7210 4785);
FORCEPROP 0 LASTPIN (-7200 5225) $PN 211
J 2
(-7210 5235);
DISPLAY 0.680851 (-7210 5235);
PAINT MONO (-7210 5235);
FORCEPROP 0 LASTPIN (-7200 4825) $PN 221
J 2
(-7210 4835);
DISPLAY 0.680851 (-7210 4835);
PAINT MONO (-7210 4835);
FORCEPROP 0 LASTPIN (-7200 5275) $PN 68
J 2
(-7210 5285);
DISPLAY 0.680851 (-7210 5285);
PAINT MONO (-7210 5285);
FORCEPROP 0 LASTPIN (-7200 4875) $PN 78
J 2
(-7210 4885);
DISPLAY 0.680851 (-7210 4885);
PAINT MONO (-7210 4885);
FORCEPROP 0 LASTPIN (-7200 5325) $PN 213
J 2
(-7210 5335);
DISPLAY 0.680851 (-7210 5335);
PAINT MONO (-7210 5335);
FORCEPROP 0 LASTPIN (-7200 4925) $PN 223
J 2
(-7210 4935);
DISPLAY 0.680851 (-7210 4935);
PAINT MONO (-7210 4935);
FORCEPROP 0 LASTPIN (-7200 5375) $PN 70
J 2
(-7210 5385);
DISPLAY 0.680851 (-7210 5385);
PAINT MONO (-7210 5385);
FORCEPROP 0 LASTPIN (-7200 4975) $PN 80
J 2
(-7210 4985);
DISPLAY 0.680851 (-7210 4985);
PAINT MONO (-7210 4985);
FORCEPROP 0 LASTPIN (-7200 5425) $PN 215
J 2
(-7210 5435);
DISPLAY 0.680851 (-7210 5435);
PAINT MONO (-7210 5435);
FORCEPROP 0 LASTPIN (-7200 5025) $PN 225
J 2
(-7210 5035);
DISPLAY 0.680851 (-7210 5035);
PAINT MONO (-7210 5035);
FORCEPROP 0 LASTPIN (-7200 5475) $PN 72
J 2
(-7210 5485);
DISPLAY 0.680851 (-7210 5485);
PAINT MONO (-7210 5485);
FORCEPROP 0 LASTPIN (-7200 5075) $PN 82
J 2
(-7210 5085);
DISPLAY 0.680851 (-7210 5085);
PAINT MONO (-7210 5085);
FORCEPROP 0 LASTPIN (-7200 3725) $PN 51
J 2
(-7210 3735);
DISPLAY 0.680851 (-7210 3735);
PAINT MONO (-7210 3735);
FORCEPROP 0 LASTPIN (-7200 3275) $PN 96
J 2
(-7210 3285);
DISPLAY 0.680851 (-7210 3285);
PAINT MONO (-7210 3285);
FORCEPROP 0 LASTPIN (-7200 3775) $PN 53
J 2
(-7210 3785);
DISPLAY 0.680851 (-7210 3785);
PAINT MONO (-7210 3785);
FORCEPROP 0 LASTPIN (-7200 3325) $PN 98
J 2
(-7210 3335);
DISPLAY 0.680851 (-7210 3335);
PAINT MONO (-7210 3335);
FORCEPROP 0 LASTPIN (-7200 3825) $PN 196
J 2
(-7210 3835);
DISPLAY 0.680851 (-7210 3835);
PAINT MONO (-7210 3835);
FORCEPROP 0 LASTPIN (-7200 3375) $PN 241
J 2
(-7210 3385);
DISPLAY 0.680851 (-7210 3385);
PAINT MONO (-7210 3385);
FORCEPROP 0 LASTPIN (-7200 3875) $PN 198
J 2
(-7210 3885);
DISPLAY 0.680851 (-7210 3885);
PAINT MONO (-7210 3885);
FORCEPROP 0 LASTPIN (-7200 3425) $PN 243
J 2
(-7210 3435);
DISPLAY 0.680851 (-7210 3435);
PAINT MONO (-7210 3435);
FORCEPROP 0 LASTPIN (-7200 3925) $PN 58
J 2
(-7210 3935);
DISPLAY 0.680851 (-7210 3935);
PAINT MONO (-7210 3935);
FORCEPROP 0 LASTPIN (-7200 3475) $PN 89
J 2
(-7210 3485);
DISPLAY 0.680851 (-7210 3485);
PAINT MONO (-7210 3485);
FORCEPROP 0 LASTPIN (-7200 3975) $PN 60
J 2
(-7210 3985);
DISPLAY 0.680851 (-7210 3985);
PAINT MONO (-7210 3985);
FORCEPROP 0 LASTPIN (-7200 3525) $PN 91
J 2
(-7210 3535);
DISPLAY 0.680851 (-7210 3535);
PAINT MONO (-7210 3535);
FORCEPROP 0 LASTPIN (-7200 4025) $PN 203
J 2
(-7210 4035);
DISPLAY 0.680851 (-7210 4035);
PAINT MONO (-7210 4035);
FORCEPROP 0 LASTPIN (-7200 3575) $PN 234
J 2
(-7210 3585);
DISPLAY 0.680851 (-7210 3585);
PAINT MONO (-7210 3585);
FORCEPROP 0 LASTPIN (-7200 4075) $PN 205
J 2
(-7210 4085);
DISPLAY 0.680851 (-7210 4085);
PAINT MONO (-7210 4085);
FORCEPROP 0 LASTPIN (-7200 3625) $PN 236
J 2
(-7210 3635);
DISPLAY 0.680851 (-7210 3635);
PAINT MONO (-7210 3635);
FORCEPROP 0 LASTPIN (-7200 4175) $PN 218
J 2
(-7210 4185);
DISPLAY 0.680851 (-7210 4185);
PAINT MONO (-7210 4185);
FORCEPROP 0 LASTPIN (-7200 4225) $PN 217
J 2
(-7210 4235);
DISPLAY 0.680851 (-7210 4235);
PAINT MONO (-7210 4235);
FORCEPROP 0 LASTPIN (-7200 4475) $PN 64
J 2
(-7210 4485);
DISPLAY 0.680851 (-7210 4485);
PAINT MONO (-7210 4485);
FORCEPROP 0 LASTPIN (-7200 4325) $PN 84
J 2
(-7210 4335);
DISPLAY 0.680851 (-7210 4335);
PAINT MONO (-7210 4335);
FORCEPROP 0 LASTPIN (-7200 4525) $PN 209
J 2
(-7210 4535);
DISPLAY 0.680851 (-7210 4535);
PAINT MONO (-7210 4535);
FORCEPROP 0 LASTPIN (-7200 4375) $PN 229
J 2
(-7210 4385);
DISPLAY 0.680851 (-7210 4385);
PAINT MONO (-7210 4385);
FORCEPROP 0 LASTPIN (-6000 3925) $PN 7
J 0
(-5990 3935);
DISPLAY 0.680851 (-5990 3935);
PAINT MONO (-5990 3935);
FORCEPROP 0 LASTPIN (-6000 2275) $PN 100
J 0
(-5990 2285);
DISPLAY 0.680851 (-5990 2285);
PAINT MONO (-5990 2285);
FORCEPROP 0 LASTPIN (-6000 3975) $PN 9
J 0
(-5990 3985);
DISPLAY 0.680851 (-5990 3985);
PAINT MONO (-5990 3985);
FORCEPROP 0 LASTPIN (-6000 2325) $PN 102
J 0
(-5990 2335);
DISPLAY 0.680851 (-5990 2335);
PAINT MONO (-5990 2335);
FORCEPROP 0 LASTPIN (-6000 4025) $PN 152
J 0
(-5990 4035);
DISPLAY 0.680851 (-5990 4035);
PAINT MONO (-5990 4035);
FORCEPROP 0 LASTPIN (-6000 2375) $PN 245
J 0
(-5990 2385);
DISPLAY 0.680851 (-5990 2385);
PAINT MONO (-5990 2385);
FORCEPROP 0 LASTPIN (-6000 4075) $PN 154
J 0
(-5990 4085);
DISPLAY 0.680851 (-5990 4085);
PAINT MONO (-5990 4085);
FORCEPROP 0 LASTPIN (-6000 2425) $PN 247
J 0
(-5990 2435);
DISPLAY 0.680851 (-5990 2435);
PAINT MONO (-5990 2435);
FORCEPROP 0 LASTPIN (-6000 4125) $PN 14
J 0
(-5990 4135);
DISPLAY 0.680851 (-5990 4135);
PAINT MONO (-5990 4135);
FORCEPROP 0 LASTPIN (-6000 2475) $PN 107
J 0
(-5990 2485);
DISPLAY 0.680851 (-5990 2485);
PAINT MONO (-5990 2485);
FORCEPROP 0 LASTPIN (-6000 4175) $PN 16
J 0
(-5990 4185);
DISPLAY 0.680851 (-5990 4185);
PAINT MONO (-5990 4185);
FORCEPROP 0 LASTPIN (-6000 2525) $PN 109
J 0
(-5990 2535);
DISPLAY 0.680851 (-5990 2535);
PAINT MONO (-5990 2535);
FORCEPROP 0 LASTPIN (-6000 4225) $PN 159
J 0
(-5990 4235);
DISPLAY 0.680851 (-5990 4235);
PAINT MONO (-5990 4235);
FORCEPROP 0 LASTPIN (-6000 2575) $PN 252
J 0
(-5990 2585);
DISPLAY 0.680851 (-5990 2585);
PAINT MONO (-5990 2585);
FORCEPROP 0 LASTPIN (-6000 4275) $PN 161
J 0
(-5990 4285);
DISPLAY 0.680851 (-5990 4285);
PAINT MONO (-5990 4285);
FORCEPROP 0 LASTPIN (-6000 2625) $PN 254
J 0
(-5990 2635);
DISPLAY 0.680851 (-5990 2635);
PAINT MONO (-5990 2635);
FORCEPROP 0 LASTPIN (-6000 4325) $PN 18
J 0
(-5990 4335);
DISPLAY 0.680851 (-5990 4335);
PAINT MONO (-5990 4335);
FORCEPROP 0 LASTPIN (-6000 2675) $PN 111
J 0
(-5990 2685);
DISPLAY 0.680851 (-5990 2685);
PAINT MONO (-5990 2685);
FORCEPROP 0 LASTPIN (-6000 4375) $PN 20
J 0
(-5990 4385);
DISPLAY 0.680851 (-5990 4385);
PAINT MONO (-5990 4385);
FORCEPROP 0 LASTPIN (-6000 2725) $PN 113
J 0
(-5990 2735);
DISPLAY 0.680851 (-5990 2735);
PAINT MONO (-5990 2735);
FORCEPROP 0 LASTPIN (-6000 4425) $PN 163
J 0
(-5990 4435);
DISPLAY 0.680851 (-5990 4435);
PAINT MONO (-5990 4435);
FORCEPROP 0 LASTPIN (-6000 2775) $PN 256
J 0
(-5990 2785);
DISPLAY 0.680851 (-5990 2785);
PAINT MONO (-5990 2785);
FORCEPROP 0 LASTPIN (-6000 4475) $PN 165
J 0
(-5990 4485);
DISPLAY 0.680851 (-5990 4485);
PAINT MONO (-5990 4485);
FORCEPROP 0 LASTPIN (-6000 2825) $PN 258
J 0
(-5990 2835);
DISPLAY 0.680851 (-5990 2835);
PAINT MONO (-5990 2835);
FORCEPROP 0 LASTPIN (-6000 4525) $PN 25
J 0
(-5990 4535);
DISPLAY 0.680851 (-5990 4535);
PAINT MONO (-5990 4535);
FORCEPROP 0 LASTPIN (-6000 2875) $PN 118
J 0
(-5990 2885);
DISPLAY 0.680851 (-5990 2885);
PAINT MONO (-5990 2885);
FORCEPROP 0 LASTPIN (-6000 4575) $PN 27
J 0
(-5990 4585);
DISPLAY 0.680851 (-5990 4585);
PAINT MONO (-5990 4585);
FORCEPROP 0 LASTPIN (-6000 2925) $PN 120
J 0
(-5990 2935);
DISPLAY 0.680851 (-5990 2935);
PAINT MONO (-5990 2935);
FORCEPROP 0 LASTPIN (-6000 4625) $PN 170
J 0
(-5990 4635);
DISPLAY 0.680851 (-5990 4635);
PAINT MONO (-5990 4635);
FORCEPROP 0 LASTPIN (-6000 2975) $PN 263
J 0
(-5990 2985);
DISPLAY 0.680851 (-5990 2985);
PAINT MONO (-5990 2985);
FORCEPROP 0 LASTPIN (-6000 4675) $PN 172
J 0
(-5990 4685);
DISPLAY 0.680851 (-5990 4685);
PAINT MONO (-5990 4685);
FORCEPROP 0 LASTPIN (-6000 3025) $PN 265
J 0
(-5990 3035);
DISPLAY 0.680851 (-5990 3035);
PAINT MONO (-5990 3035);
FORCEPROP 0 LASTPIN (-6000 4725) $PN 29
J 0
(-5990 4735);
DISPLAY 0.680851 (-5990 4735);
PAINT MONO (-5990 4735);
FORCEPROP 0 LASTPIN (-6000 3075) $PN 122
J 0
(-5990 3085);
DISPLAY 0.680851 (-5990 3085);
PAINT MONO (-5990 3085);
FORCEPROP 0 LASTPIN (-6000 4775) $PN 31
J 0
(-5990 4785);
DISPLAY 0.680851 (-5990 4785);
PAINT MONO (-5990 4785);
FORCEPROP 0 LASTPIN (-6000 3125) $PN 124
J 0
(-5990 3135);
DISPLAY 0.680851 (-5990 3135);
PAINT MONO (-5990 3135);
FORCEPROP 0 LASTPIN (-6000 4825) $PN 174
J 0
(-5990 4835);
DISPLAY 0.680851 (-5990 4835);
PAINT MONO (-5990 4835);
FORCEPROP 0 LASTPIN (-6000 3175) $PN 267
J 0
(-5990 3185);
DISPLAY 0.680851 (-5990 3185);
PAINT MONO (-5990 3185);
FORCEPROP 0 LASTPIN (-6000 4875) $PN 176
J 0
(-5990 4885);
DISPLAY 0.680851 (-5990 4885);
PAINT MONO (-5990 4885);
FORCEPROP 0 LASTPIN (-6000 3225) $PN 269
J 0
(-5990 3235);
DISPLAY 0.680851 (-5990 3235);
PAINT MONO (-5990 3235);
FORCEPROP 0 LASTPIN (-6000 4925) $PN 36
J 0
(-5990 4935);
DISPLAY 0.680851 (-5990 4935);
PAINT MONO (-5990 4935);
FORCEPROP 0 LASTPIN (-6000 3275) $PN 129
J 0
(-5990 3285);
DISPLAY 0.680851 (-5990 3285);
PAINT MONO (-5990 3285);
FORCEPROP 0 LASTPIN (-6000 4975) $PN 38
J 0
(-5990 4985);
DISPLAY 0.680851 (-5990 4985);
PAINT MONO (-5990 4985);
FORCEPROP 0 LASTPIN (-6000 3325) $PN 131
J 0
(-5990 3335);
DISPLAY 0.680851 (-5990 3335);
PAINT MONO (-5990 3335);
FORCEPROP 0 LASTPIN (-6000 5025) $PN 181
J 0
(-5990 5035);
DISPLAY 0.680851 (-5990 5035);
PAINT MONO (-5990 5035);
FORCEPROP 0 LASTPIN (-6000 3375) $PN 274
J 0
(-5990 3385);
DISPLAY 0.680851 (-5990 3385);
PAINT MONO (-5990 3385);
FORCEPROP 0 LASTPIN (-6000 5075) $PN 183
J 0
(-5990 5085);
DISPLAY 0.680851 (-5990 5085);
PAINT MONO (-5990 5085);
FORCEPROP 0 LASTPIN (-6000 3425) $PN 276
J 0
(-5990 3435);
DISPLAY 0.680851 (-5990 3435);
PAINT MONO (-5990 3435);
FORCEPROP 0 LASTPIN (-6000 5125) $PN 40
J 0
(-5990 5135);
DISPLAY 0.680851 (-5990 5135);
PAINT MONO (-5990 5135);
FORCEPROP 0 LASTPIN (-6000 3475) $PN 133
J 0
(-5990 3485);
DISPLAY 0.680851 (-5990 3485);
PAINT MONO (-5990 3485);
FORCEPROP 0 LASTPIN (-6000 5175) $PN 42
J 0
(-5990 5185);
DISPLAY 0.680851 (-5990 5185);
PAINT MONO (-5990 5185);
FORCEPROP 0 LASTPIN (-6000 3525) $PN 135
J 0
(-5990 3535);
DISPLAY 0.680851 (-5990 3535);
PAINT MONO (-5990 3535);
FORCEPROP 0 LASTPIN (-6000 5225) $PN 185
J 0
(-5990 5235);
DISPLAY 0.680851 (-5990 5235);
PAINT MONO (-5990 5235);
FORCEPROP 0 LASTPIN (-6000 3575) $PN 278
J 0
(-5990 3585);
DISPLAY 0.680851 (-5990 3585);
PAINT MONO (-5990 3585);
FORCEPROP 0 LASTPIN (-6000 5275) $PN 187
J 0
(-5990 5285);
DISPLAY 0.680851 (-5990 5285);
PAINT MONO (-5990 5285);
FORCEPROP 0 LASTPIN (-6000 3625) $PN 280
J 0
(-5990 3635);
DISPLAY 0.680851 (-5990 3635);
PAINT MONO (-5990 3635);
FORCEPROP 0 LASTPIN (-6000 5325) $PN 47
J 0
(-5990 5335);
DISPLAY 0.680851 (-5990 5335);
PAINT MONO (-5990 5335);
FORCEPROP 0 LASTPIN (-6000 3675) $PN 140
J 0
(-5990 3685);
DISPLAY 0.680851 (-5990 3685);
PAINT MONO (-5990 3685);
FORCEPROP 0 LASTPIN (-6000 5375) $PN 49
J 0
(-5990 5385);
DISPLAY 0.680851 (-5990 5385);
PAINT MONO (-5990 5385);
FORCEPROP 0 LASTPIN (-6000 3725) $PN 142
J 0
(-5990 3735);
DISPLAY 0.680851 (-5990 3735);
PAINT MONO (-5990 3735);
FORCEPROP 0 LASTPIN (-6000 5425) $PN 192
J 0
(-5990 5435);
DISPLAY 0.680851 (-5990 5435);
PAINT MONO (-5990 5435);
FORCEPROP 0 LASTPIN (-6000 3775) $PN 285
J 0
(-5990 3785);
DISPLAY 0.680851 (-5990 3785);
PAINT MONO (-5990 3785);
FORCEPROP 0 LASTPIN (-6000 5475) $PN 194
J 0
(-5990 5485);
DISPLAY 0.680851 (-5990 5485);
PAINT MONO (-5990 5485);
FORCEPROP 0 LASTPIN (-6000 3825) $PN 287
J 0
(-5990 3835);
DISPLAY 0.680851 (-5990 3835);
PAINT MONO (-5990 3835);
FORCEPROP 0 LASTPIN (-7200 2975) $PN 148
J 2
(-7210 2985);
DISPLAY 0.680851 (-7210 2985);
PAINT MONO (-7210 2985);
FORCEPROP 0 LASTPIN (-7200 2875) $PN 4
J 2
(-7210 2885);
DISPLAY 0.680851 (-7210 2885);
PAINT MONO (-7210 2885);
FORCEPROP 0 LASTPIN (-7200 2925) $PN 5
J 2
(-7210 2935);
DISPLAY 0.680851 (-7210 2935);
PAINT MONO (-7210 2935);
FORCEPROP 0 LASTPIN (-7200 2075) $PN 86
J 2
(-7210 2085);
DISPLAY 0.680851 (-7210 2085);
PAINT MONO (-7210 2085);
FORCEPROP 0 LASTPIN (-7200 2025) $PN 87
J 2
(-7210 2035);
DISPLAY 0.680851 (-7210 2035);
PAINT MONO (-7210 2035);
FORCEPROP 0 LASTPIN (-7200 4675) $PN 74
J 2
(-7210 4685);
DISPLAY 0.680851 (-7210 4685);
PAINT MONO (-7210 4685);
FORCEPROP 0 LASTPIN (-7200 4625) $PN 227
J 2
(-7210 4635);
DISPLAY 0.680851 (-7210 4635);
PAINT MONO (-7210 4635);
FORCEPROP 0 LASTPIN (-7200 2625) $PN 147
J 2
(-7210 2635);
DISPLAY 0.680851 (-7210 2635);
PAINT MONO (-7210 2635);
FORCEPROP 0 LASTPIN (-7200 3175) $PN 207
J 2
(-7210 3185);
DISPLAY 0.680851 (-7210 3185);
PAINT MONO (-7210 3185);
FORCEPROP 0 LASTPIN (-7200 2225) $PN 2
J 2
(-7210 2235);
DISPLAY 0.680851 (-7210 2235);
PAINT MONO (-7210 2235);
FORCEPROP 0 LASTPIN (-7200 2275) $PN 144
J 2
(-7210 2285);
DISPLAY 0.680851 (-7210 2285);
PAINT MONO (-7210 2285);
FORCEPROP 0 LASTPIN (-7200 2325) $PN 149
J 2
(-7210 2335);
DISPLAY 0.680851 (-7210 2335);
PAINT MONO (-7210 2335);
FORCEPROP 0 LASTPIN (-7200 2375) $PN 150
J 2
(-7210 2385);
DISPLAY 0.680851 (-7210 2385);
PAINT MONO (-7210 2385);
FORCEPROP 0 LASTPIN (-7200 2425) $PN 220
J 2
(-7210 2435);
DISPLAY 0.680851 (-7210 2435);
PAINT MONO (-7210 2435);
FORCEPROP 0 LASTPIN (-7200 2475) $PN 231
J 2
(-7210 2485);
DISPLAY 0.680851 (-7210 2485);
PAINT MONO (-7210 2485);
FORCEPROP 0 LASTPIN (-7200 2525) $PN 232
J 2
(-7210 2535);
DISPLAY 0.680851 (-7210 2535);
PAINT MONO (-7210 2535);
FORCEPROP 0 LASTPIN (-7200 3025) $PN 3
J 2
(-7210 3035);
DISPLAY 0.680851 (-7210 3035);
PAINT MONO (-7210 3035);
FORCEPROP 2 LAST VALUE SCONN288_DDR506112002KQ
J 0
(-7050 5850);
DISPLAY 0.489362 (-7050 5850);
PAINT SKYBLUE (-7050 5850);
FORCEPROP 2 LAST PART_TYPE SMLF
J 0
(-7050 5900);
DISPLAY 1.021277 (-7050 5900);
FORCEPROP 1 LAST MATERIAL IO
J 0
(-7050 5650);
DISPLAY 0.468085 (-7050 5650);
PAINT SKYBLUE (-7050 5650);
FORCEPROP 1 LAST CDS_LMAN_SYM_OUTLINE -450,1900,450,-1850
J 0
(-6600 3725);
DISPLAY 0.468085 (-6600 3725);
PAINT GREEN (-6600 3725);
DISPLAY INVISIBLE (-6600 3725);
FORCEPROP 1 LAST NEEDS_NO_SIZE TRUE
J 0
(-6600 3725);
DISPLAY 0.723404 (-6600 3725);
PAINT GREEN (-6600 3725);
DISPLAY INVISIBLE (-6600 3725);
FORCEPROP 2 LAST CDS_LIB pure_quanta
J 0
(-6600 3725);
DISPLAY INVISIBLE (-6600 3725);
FORCEPROP 1 LAST PATH I22
J 0
(-6600 3725);
DISPLAY 0.723404 (-6600 3725);
PAINT GREEN (-6600 3725);
DISPLAY INVISIBLE (-6600 3725);
FORCEPROP 1 LAST PART_NUMBER DFHST8FS479
J 0
(-7050 5725);
DISPLAY 0.468085 (-7050 5725);
PAINT SKYBLUE (-7050 5725);
DISPLAY INVISIBLE (-7050 5725);
FORCEADD TAP..1
(-3225 3800);
FORCEPROP 3 LASTPIN (-3275 3800) SIG_NAME M_A_CPU1_SA_DQS_DP<1>
J 0
(-3265 3810);
DISPLAY 0.659574 (-3265 3810);
PAINT MONO (-3265 3810);
DISPLAY INVISIBLE (-3265 3810);
FORCEPROP 1 LASTPIN (-3275 3800) BN 1
J 0
(-3287 3808);
DISPLAY 0.489362 (-3287 3808);
PAINT GREEN (-3287 3808);
FORCEPROP 2 LAST CDS_LIB mstr_standard
J 0
(-3225 3800);
DISPLAY 0.723404 (-3225 3800);
PAINT MONO (-3225 3800);
DISPLAY INVISIBLE (-3225 3800);
FORCEPROP 1 LAST BODY_TYPE PLUMBING
J 0
(-3225 3850);
DISPLAY 0.872340 (-3225 3850);
PAINT GREEN (-3225 3850);
DISPLAY INVISIBLE (-3225 3850);
FORCEPROP 1 LAST HDL_TAP TRUE
J 0
(-2900 3675);
DISPLAY 0.872340 (-2900 3675);
DISPLAY INVISIBLE (-2900 3675);
FORCEPROP 1 LAST PATH I220
J 0
(-3227 3800);
DISPLAY 0.872340 (-3227 3800);
PAINT GREEN (-3227 3800);
DISPLAY INVISIBLE (-3227 3800);
FORCEADD TAP..1
(-3225 3550);
FORCEPROP 3 LASTPIN (-3275 3550) SIG_NAME M_A_CPU1_SB_DQS_DP<9>
J 0
(-3265 3560);
DISPLAY 0.659574 (-3265 3560);
PAINT MONO (-3265 3560);
DISPLAY INVISIBLE (-3265 3560);
FORCEPROP 1 LASTPIN (-3275 3550) BN 9
J 0
(-3287 3558);
DISPLAY 0.489362 (-3287 3558);
PAINT GREEN (-3287 3558);
FORCEPROP 2 LAST CDS_LIB mstr_standard
J 0
(-3225 3550);
DISPLAY 0.723404 (-3225 3550);
PAINT MONO (-3225 3550);
DISPLAY INVISIBLE (-3225 3550);
FORCEPROP 1 LAST BODY_TYPE PLUMBING
J 0
(-3225 3600);
DISPLAY 0.872340 (-3225 3600);
PAINT GREEN (-3225 3600);
DISPLAY INVISIBLE (-3225 3600);
FORCEPROP 1 LAST HDL_TAP TRUE
J 0
(-2900 3425);
DISPLAY 0.872340 (-2900 3425);
DISPLAY INVISIBLE (-2900 3425);
FORCEPROP 1 LAST PATH I221
J 0
(-3227 3550);
DISPLAY 0.872340 (-3227 3550);
PAINT GREEN (-3227 3550);
DISPLAY INVISIBLE (-3227 3550);
FORCEADD TAP..1
(-3225 3450);
FORCEPROP 3 LASTPIN (-3275 3450) SIG_NAME M_A_CPU1_SB_DQS_DP<8>
J 0
(-3265 3460);
DISPLAY 0.659574 (-3265 3460);
PAINT MONO (-3265 3460);
DISPLAY INVISIBLE (-3265 3460);
FORCEPROP 1 LASTPIN (-3275 3450) BN 8
J 0
(-3287 3458);
DISPLAY 0.489362 (-3287 3458);
PAINT GREEN (-3287 3458);
FORCEPROP 2 LAST CDS_LIB mstr_standard
J 0
(-3225 3450);
DISPLAY 0.723404 (-3225 3450);
PAINT MONO (-3225 3450);
DISPLAY INVISIBLE (-3225 3450);
FORCEPROP 1 LAST BODY_TYPE PLUMBING
J 0
(-3225 3500);
DISPLAY 0.872340 (-3225 3500);
PAINT GREEN (-3225 3500);
DISPLAY INVISIBLE (-3225 3500);
FORCEPROP 1 LAST HDL_TAP TRUE
J 0
(-2900 3325);
DISPLAY 0.872340 (-2900 3325);
DISPLAY INVISIBLE (-2900 3325);
FORCEPROP 1 LAST PATH I222
J 0
(-3227 3450);
DISPLAY 0.872340 (-3227 3450);
PAINT GREEN (-3227 3450);
DISPLAY INVISIBLE (-3227 3450);
FORCEADD TAP..1
(-3225 3350);
FORCEPROP 3 LASTPIN (-3275 3350) SIG_NAME M_A_CPU1_SB_DQS_DP<7>
J 0
(-3265 3360);
DISPLAY 0.659574 (-3265 3360);
PAINT MONO (-3265 3360);
DISPLAY INVISIBLE (-3265 3360);
FORCEPROP 1 LASTPIN (-3275 3350) BN 7
J 0
(-3287 3358);
DISPLAY 0.489362 (-3287 3358);
PAINT GREEN (-3287 3358);
FORCEPROP 2 LAST CDS_LIB mstr_standard
J 0
(-3225 3350);
DISPLAY 0.723404 (-3225 3350);
PAINT MONO (-3225 3350);
DISPLAY INVISIBLE (-3225 3350);
FORCEPROP 1 LAST BODY_TYPE PLUMBING
J 0
(-3225 3400);
DISPLAY 0.872340 (-3225 3400);
PAINT GREEN (-3225 3400);
DISPLAY INVISIBLE (-3225 3400);
FORCEPROP 1 LAST HDL_TAP TRUE
J 0
(-2900 3225);
DISPLAY 0.872340 (-2900 3225);
DISPLAY INVISIBLE (-2900 3225);
FORCEPROP 1 LAST PATH I223
J 0
(-3227 3350);
DISPLAY 0.872340 (-3227 3350);
PAINT GREEN (-3227 3350);
DISPLAY INVISIBLE (-3227 3350);
FORCEADD TAP..1
(-3025 3200);
FORCEPROP 3 LASTPIN (-3075 3200) SIG_NAME M_A_CPU1_SB_DQS_DN<6>
J 0
(-3065 3210);
DISPLAY 0.659574 (-3065 3210);
PAINT MONO (-3065 3210);
DISPLAY INVISIBLE (-3065 3210);
FORCEPROP 1 LASTPIN (-3075 3200) BN 6
J 0
(-3087 3208);
DISPLAY 0.489362 (-3087 3208);
PAINT GREEN (-3087 3208);
FORCEPROP 2 LAST CDS_LIB mstr_standard
J 0
(-3025 3200);
DISPLAY 0.723404 (-3025 3200);
PAINT MONO (-3025 3200);
DISPLAY INVISIBLE (-3025 3200);
FORCEPROP 1 LAST BODY_TYPE PLUMBING
J 0
(-3025 3250);
DISPLAY 0.872340 (-3025 3250);
PAINT GREEN (-3025 3250);
DISPLAY INVISIBLE (-3025 3250);
FORCEPROP 1 LAST HDL_TAP TRUE
J 0
(-2700 3075);
DISPLAY 0.872340 (-2700 3075);
DISPLAY INVISIBLE (-2700 3075);
FORCEPROP 1 LAST PATH I224
J 0
(-3027 3200);
DISPLAY 0.872340 (-3027 3200);
PAINT GREEN (-3027 3200);
DISPLAY INVISIBLE (-3027 3200);
FORCEADD TAP..1
(-3025 3100);
FORCEPROP 3 LASTPIN (-3075 3100) SIG_NAME M_A_CPU1_SB_DQS_DN<5>
J 0
(-3065 3110);
DISPLAY 0.659574 (-3065 3110);
PAINT MONO (-3065 3110);
DISPLAY INVISIBLE (-3065 3110);
FORCEPROP 1 LASTPIN (-3075 3100) BN 5
J 0
(-3087 3108);
DISPLAY 0.489362 (-3087 3108);
PAINT GREEN (-3087 3108);
FORCEPROP 2 LAST CDS_LIB mstr_standard
J 0
(-3025 3100);
DISPLAY 0.723404 (-3025 3100);
PAINT MONO (-3025 3100);
DISPLAY INVISIBLE (-3025 3100);
FORCEPROP 1 LAST BODY_TYPE PLUMBING
J 0
(-3025 3150);
DISPLAY 0.872340 (-3025 3150);
PAINT GREEN (-3025 3150);
DISPLAY INVISIBLE (-3025 3150);
FORCEPROP 1 LAST HDL_TAP TRUE
J 0
(-2700 2975);
DISPLAY 0.872340 (-2700 2975);
DISPLAY INVISIBLE (-2700 2975);
FORCEPROP 1 LAST PATH I225
J 0
(-3027 3100);
DISPLAY 0.872340 (-3027 3100);
PAINT GREEN (-3027 3100);
DISPLAY INVISIBLE (-3027 3100);
FORCEADD TAP..1
(-3025 3000);
FORCEPROP 3 LASTPIN (-3075 3000) SIG_NAME M_A_CPU1_SB_DQS_DN<4>
J 0
(-3065 3010);
DISPLAY 0.659574 (-3065 3010);
PAINT MONO (-3065 3010);
DISPLAY INVISIBLE (-3065 3010);
FORCEPROP 1 LASTPIN (-3075 3000) BN 4
J 0
(-3087 3008);
DISPLAY 0.489362 (-3087 3008);
PAINT GREEN (-3087 3008);
FORCEPROP 2 LAST CDS_LIB mstr_standard
J 0
(-3025 3000);
DISPLAY 0.723404 (-3025 3000);
PAINT MONO (-3025 3000);
DISPLAY INVISIBLE (-3025 3000);
FORCEPROP 1 LAST BODY_TYPE PLUMBING
J 0
(-3025 3050);
DISPLAY 0.872340 (-3025 3050);
PAINT GREEN (-3025 3050);
DISPLAY INVISIBLE (-3025 3050);
FORCEPROP 1 LAST HDL_TAP TRUE
J 0
(-2700 2875);
DISPLAY 0.872340 (-2700 2875);
DISPLAY INVISIBLE (-2700 2875);
FORCEPROP 1 LAST PATH I226
J 0
(-3027 3000);
DISPLAY 0.872340 (-3027 3000);
PAINT GREEN (-3027 3000);
DISPLAY INVISIBLE (-3027 3000);
FORCEADD TAP..1
(-3025 2800);
FORCEPROP 3 LASTPIN (-3075 2800) SIG_NAME M_A_CPU1_SB_DQS_DN<2>
J 0
(-3065 2810);
DISPLAY 0.659574 (-3065 2810);
PAINT MONO (-3065 2810);
DISPLAY INVISIBLE (-3065 2810);
FORCEPROP 1 LASTPIN (-3075 2800) BN 2
J 0
(-3087 2808);
DISPLAY 0.489362 (-3087 2808);
PAINT GREEN (-3087 2808);
FORCEPROP 2 LAST CDS_LIB mstr_standard
J 0
(-3025 2800);
DISPLAY 0.723404 (-3025 2800);
PAINT MONO (-3025 2800);
DISPLAY INVISIBLE (-3025 2800);
FORCEPROP 1 LAST BODY_TYPE PLUMBING
J 0
(-3025 2850);
DISPLAY 0.872340 (-3025 2850);
PAINT GREEN (-3025 2850);
DISPLAY INVISIBLE (-3025 2850);
FORCEPROP 1 LAST HDL_TAP TRUE
J 0
(-2700 2675);
DISPLAY 0.872340 (-2700 2675);
DISPLAY INVISIBLE (-2700 2675);
FORCEPROP 1 LAST PATH I227
J 0
(-3027 2800);
DISPLAY 0.872340 (-3027 2800);
PAINT GREEN (-3027 2800);
DISPLAY INVISIBLE (-3027 2800);
FORCEADD TAP..1
(-3025 2900);
FORCEPROP 3 LASTPIN (-3075 2900) SIG_NAME M_A_CPU1_SB_DQS_DN<3>
J 0
(-3065 2910);
DISPLAY 0.659574 (-3065 2910);
PAINT MONO (-3065 2910);
DISPLAY INVISIBLE (-3065 2910);
FORCEPROP 1 LASTPIN (-3075 2900) BN 3
J 0
(-3087 2908);
DISPLAY 0.489362 (-3087 2908);
PAINT GREEN (-3087 2908);
FORCEPROP 2 LAST CDS_LIB mstr_standard
J 0
(-3025 2900);
DISPLAY 0.723404 (-3025 2900);
PAINT MONO (-3025 2900);
DISPLAY INVISIBLE (-3025 2900);
FORCEPROP 1 LAST BODY_TYPE PLUMBING
J 0
(-3025 2950);
DISPLAY 0.872340 (-3025 2950);
PAINT GREEN (-3025 2950);
DISPLAY INVISIBLE (-3025 2950);
FORCEPROP 1 LAST HDL_TAP TRUE
J 0
(-2700 2775);
DISPLAY 0.872340 (-2700 2775);
DISPLAY INVISIBLE (-2700 2775);
FORCEPROP 1 LAST PATH I228
J 0
(-3027 2900);
DISPLAY 0.872340 (-3027 2900);
PAINT GREEN (-3027 2900);
DISPLAY INVISIBLE (-3027 2900);
FORCEADD TAP..1
(-3225 3250);
FORCEPROP 3 LASTPIN (-3275 3250) SIG_NAME M_A_CPU1_SB_DQS_DP<6>
J 0
(-3265 3260);
DISPLAY 0.659574 (-3265 3260);
PAINT MONO (-3265 3260);
DISPLAY INVISIBLE (-3265 3260);
FORCEPROP 1 LASTPIN (-3275 3250) BN 6
J 0
(-3287 3258);
DISPLAY 0.489362 (-3287 3258);
PAINT GREEN (-3287 3258);
FORCEPROP 2 LAST CDS_LIB mstr_standard
J 0
(-3225 3250);
DISPLAY 0.723404 (-3225 3250);
PAINT MONO (-3225 3250);
DISPLAY INVISIBLE (-3225 3250);
FORCEPROP 1 LAST BODY_TYPE PLUMBING
J 0
(-3225 3300);
DISPLAY 0.872340 (-3225 3300);
PAINT GREEN (-3225 3300);
DISPLAY INVISIBLE (-3225 3300);
FORCEPROP 1 LAST HDL_TAP TRUE
J 0
(-2900 3125);
DISPLAY 0.872340 (-2900 3125);
DISPLAY INVISIBLE (-2900 3125);
FORCEPROP 1 LAST PATH I229
J 0
(-3227 3250);
DISPLAY 0.872340 (-3227 3250);
PAINT GREEN (-3227 3250);
DISPLAY INVISIBLE (-3227 3250);
FORCEADD TAP..1
R 2
(-7450 3275);
FORCEPROP 3 LASTPIN (-7400 3275) SIG_NAME M_A_CPU1_SB_CB<0>
J 0
(-7390 3285);
DISPLAY 0.659574 (-7390 3285);
PAINT MONO (-7390 3285);
DISPLAY INVISIBLE (-7390 3285);
FORCEPROP 1 LASTPIN (-7400 3275) BN 0
J 2
(-7388 3283);
DISPLAY 0.489362 (-7388 3283);
PAINT GREEN (-7388 3283);
FORCEPROP 2 LAST CDS_LIB mstr_standard
J 0
(-7450 3275);
DISPLAY 0.723404 (-7450 3275);
PAINT MONO (-7450 3275);
DISPLAY INVISIBLE (-7450 3275);
FORCEPROP 1 LAST BODY_TYPE PLUMBING
J 2
(-7450 3325);
DISPLAY 0.872340 (-7450 3325);
PAINT GREEN (-7450 3325);
DISPLAY INVISIBLE (-7450 3325);
FORCEPROP 1 LAST HDL_TAP TRUE
J 2
(-7775 3150);
DISPLAY 0.872340 (-7775 3150);
DISPLAY INVISIBLE (-7775 3150);
FORCEPROP 1 LAST PATH I23
J 2
(-7448 3275);
DISPLAY 0.872340 (-7448 3275);
PAINT GREEN (-7448 3275);
DISPLAY INVISIBLE (-7448 3275);
FORCEADD TAP..1
(-3225 3050);
FORCEPROP 3 LASTPIN (-3275 3050) SIG_NAME M_A_CPU1_SB_DQS_DP<4>
J 0
(-3265 3060);
DISPLAY 0.659574 (-3265 3060);
PAINT MONO (-3265 3060);
DISPLAY INVISIBLE (-3265 3060);
FORCEPROP 1 LASTPIN (-3275 3050) BN 4
J 0
(-3287 3058);
DISPLAY 0.489362 (-3287 3058);
PAINT GREEN (-3287 3058);
FORCEPROP 2 LAST CDS_LIB mstr_standard
J 0
(-3225 3050);
DISPLAY 0.723404 (-3225 3050);
PAINT MONO (-3225 3050);
DISPLAY INVISIBLE (-3225 3050);
FORCEPROP 1 LAST BODY_TYPE PLUMBING
J 0
(-3225 3100);
DISPLAY 0.872340 (-3225 3100);
PAINT GREEN (-3225 3100);
DISPLAY INVISIBLE (-3225 3100);
FORCEPROP 1 LAST HDL_TAP TRUE
J 0
(-2900 2925);
DISPLAY 0.872340 (-2900 2925);
DISPLAY INVISIBLE (-2900 2925);
FORCEPROP 1 LAST PATH I230
J 0
(-3227 3050);
DISPLAY 0.872340 (-3227 3050);
PAINT GREEN (-3227 3050);
DISPLAY INVISIBLE (-3227 3050);
FORCEADD TAP..1
(-3225 3150);
FORCEPROP 3 LASTPIN (-3275 3150) SIG_NAME M_A_CPU1_SB_DQS_DP<5>
J 0
(-3265 3160);
DISPLAY 0.659574 (-3265 3160);
PAINT MONO (-3265 3160);
DISPLAY INVISIBLE (-3265 3160);
FORCEPROP 1 LASTPIN (-3275 3150) BN 5
J 0
(-3287 3158);
DISPLAY 0.489362 (-3287 3158);
PAINT GREEN (-3287 3158);
FORCEPROP 2 LAST CDS_LIB mstr_standard
J 0
(-3225 3150);
DISPLAY 0.723404 (-3225 3150);
PAINT MONO (-3225 3150);
DISPLAY INVISIBLE (-3225 3150);
FORCEPROP 1 LAST BODY_TYPE PLUMBING
J 0
(-3225 3200);
DISPLAY 0.872340 (-3225 3200);
PAINT GREEN (-3225 3200);
DISPLAY INVISIBLE (-3225 3200);
FORCEPROP 1 LAST HDL_TAP TRUE
J 0
(-2900 3025);
DISPLAY 0.872340 (-2900 3025);
DISPLAY INVISIBLE (-2900 3025);
FORCEPROP 1 LAST PATH I231
J 0
(-3227 3150);
DISPLAY 0.872340 (-3227 3150);
PAINT GREEN (-3227 3150);
DISPLAY INVISIBLE (-3227 3150);
FORCEADD TAP..1
(-3225 2950);
FORCEPROP 3 LASTPIN (-3275 2950) SIG_NAME M_A_CPU1_SB_DQS_DP<3>
J 0
(-3265 2960);
DISPLAY 0.659574 (-3265 2960);
PAINT MONO (-3265 2960);
DISPLAY INVISIBLE (-3265 2960);
FORCEPROP 1 LASTPIN (-3275 2950) BN 3
J 0
(-3287 2958);
DISPLAY 0.489362 (-3287 2958);
PAINT GREEN (-3287 2958);
FORCEPROP 2 LAST CDS_LIB mstr_standard
J 0
(-3225 2950);
DISPLAY 0.723404 (-3225 2950);
PAINT MONO (-3225 2950);
DISPLAY INVISIBLE (-3225 2950);
FORCEPROP 1 LAST BODY_TYPE PLUMBING
J 0
(-3225 3000);
DISPLAY 0.872340 (-3225 3000);
PAINT GREEN (-3225 3000);
DISPLAY INVISIBLE (-3225 3000);
FORCEPROP 1 LAST HDL_TAP TRUE
J 0
(-2900 2825);
DISPLAY 0.872340 (-2900 2825);
DISPLAY INVISIBLE (-2900 2825);
FORCEPROP 1 LAST PATH I232
J 0
(-3227 2950);
DISPLAY 0.872340 (-3227 2950);
PAINT GREEN (-3227 2950);
DISPLAY INVISIBLE (-3227 2950);
FORCEADD TAP..1
(-3225 2850);
FORCEPROP 3 LASTPIN (-3275 2850) SIG_NAME M_A_CPU1_SB_DQS_DP<2>
J 0
(-3265 2860);
DISPLAY 0.659574 (-3265 2860);
PAINT MONO (-3265 2860);
DISPLAY INVISIBLE (-3265 2860);
FORCEPROP 1 LASTPIN (-3275 2850) BN 2
J 0
(-3287 2858);
DISPLAY 0.489362 (-3287 2858);
PAINT GREEN (-3287 2858);
FORCEPROP 2 LAST CDS_LIB mstr_standard
J 0
(-3225 2850);
DISPLAY 0.723404 (-3225 2850);
PAINT MONO (-3225 2850);
DISPLAY INVISIBLE (-3225 2850);
FORCEPROP 1 LAST BODY_TYPE PLUMBING
J 0
(-3225 2900);
DISPLAY 0.872340 (-3225 2900);
PAINT GREEN (-3225 2900);
DISPLAY INVISIBLE (-3225 2900);
FORCEPROP 1 LAST HDL_TAP TRUE
J 0
(-2900 2725);
DISPLAY 0.872340 (-2900 2725);
DISPLAY INVISIBLE (-2900 2725);
FORCEPROP 1 LAST PATH I233
J 0
(-3227 2850);
DISPLAY 0.872340 (-3227 2850);
PAINT GREEN (-3227 2850);
DISPLAY INVISIBLE (-3227 2850);
FORCEADD TAP..1
(-3025 2700);
FORCEPROP 3 LASTPIN (-3075 2700) SIG_NAME M_A_CPU1_SB_DQS_DN<1>
J 0
(-3065 2710);
DISPLAY 0.659574 (-3065 2710);
PAINT MONO (-3065 2710);
DISPLAY INVISIBLE (-3065 2710);
FORCEPROP 1 LASTPIN (-3075 2700) BN 1
J 0
(-3087 2708);
DISPLAY 0.489362 (-3087 2708);
PAINT GREEN (-3087 2708);
FORCEPROP 2 LAST CDS_LIB mstr_standard
J 0
(-3025 2700);
DISPLAY 0.723404 (-3025 2700);
PAINT MONO (-3025 2700);
DISPLAY INVISIBLE (-3025 2700);
FORCEPROP 1 LAST BODY_TYPE PLUMBING
J 0
(-3025 2750);
DISPLAY 0.872340 (-3025 2750);
PAINT GREEN (-3025 2750);
DISPLAY INVISIBLE (-3025 2750);
FORCEPROP 1 LAST HDL_TAP TRUE
J 0
(-2700 2575);
DISPLAY 0.872340 (-2700 2575);
DISPLAY INVISIBLE (-2700 2575);
FORCEPROP 1 LAST PATH I234
J 0
(-3027 2700);
DISPLAY 0.872340 (-3027 2700);
PAINT GREEN (-3027 2700);
DISPLAY INVISIBLE (-3027 2700);
FORCEADD TAP..1
(-3025 2600);
FORCEPROP 3 LASTPIN (-3075 2600) SIG_NAME M_A_CPU1_SB_DQS_DN<0>
J 0
(-3065 2610);
DISPLAY 0.659574 (-3065 2610);
PAINT MONO (-3065 2610);
DISPLAY INVISIBLE (-3065 2610);
FORCEPROP 1 LASTPIN (-3075 2600) BN 0
J 0
(-3087 2608);
DISPLAY 0.489362 (-3087 2608);
PAINT GREEN (-3087 2608);
FORCEPROP 2 LAST CDS_LIB mstr_standard
J 0
(-3025 2600);
DISPLAY 0.723404 (-3025 2600);
PAINT MONO (-3025 2600);
DISPLAY INVISIBLE (-3025 2600);
FORCEPROP 1 LAST BODY_TYPE PLUMBING
J 0
(-3025 2650);
DISPLAY 0.872340 (-3025 2650);
PAINT GREEN (-3025 2650);
DISPLAY INVISIBLE (-3025 2650);
FORCEPROP 1 LAST HDL_TAP TRUE
J 0
(-2700 2475);
DISPLAY 0.872340 (-2700 2475);
DISPLAY INVISIBLE (-2700 2475);
FORCEPROP 1 LAST PATH I235
J 0
(-3027 2600);
DISPLAY 0.872340 (-3027 2600);
PAINT GREEN (-3027 2600);
DISPLAY INVISIBLE (-3027 2600);
FORCEADD TAP..1
(-3225 2650);
FORCEPROP 3 LASTPIN (-3275 2650) SIG_NAME M_A_CPU1_SB_DQS_DP<0>
J 0
(-3265 2660);
DISPLAY 0.659574 (-3265 2660);
PAINT MONO (-3265 2660);
DISPLAY INVISIBLE (-3265 2660);
FORCEPROP 1 LASTPIN (-3275 2650) BN 0
J 0
(-3287 2658);
DISPLAY 0.489362 (-3287 2658);
PAINT GREEN (-3287 2658);
FORCEPROP 2 LAST CDS_LIB mstr_standard
J 0
(-3225 2650);
DISPLAY 0.723404 (-3225 2650);
PAINT MONO (-3225 2650);
DISPLAY INVISIBLE (-3225 2650);
FORCEPROP 1 LAST BODY_TYPE PLUMBING
J 0
(-3225 2700);
DISPLAY 0.872340 (-3225 2700);
PAINT GREEN (-3225 2700);
DISPLAY INVISIBLE (-3225 2700);
FORCEPROP 1 LAST HDL_TAP TRUE
J 0
(-2900 2525);
DISPLAY 0.872340 (-2900 2525);
DISPLAY INVISIBLE (-2900 2525);
FORCEPROP 1 LAST PATH I236
J 0
(-3227 2650);
DISPLAY 0.872340 (-3227 2650);
PAINT GREEN (-3227 2650);
DISPLAY INVISIBLE (-3227 2650);
FORCEADD TAP..1
(-3225 2750);
FORCEPROP 3 LASTPIN (-3275 2750) SIG_NAME M_A_CPU1_SB_DQS_DP<1>
J 0
(-3265 2760);
DISPLAY 0.659574 (-3265 2760);
PAINT MONO (-3265 2760);
DISPLAY INVISIBLE (-3265 2760);
FORCEPROP 1 LASTPIN (-3275 2750) BN 1
J 0
(-3287 2758);
DISPLAY 0.489362 (-3287 2758);
PAINT GREEN (-3287 2758);
FORCEPROP 2 LAST CDS_LIB mstr_standard
J 0
(-3225 2750);
DISPLAY 0.723404 (-3225 2750);
PAINT MONO (-3225 2750);
DISPLAY INVISIBLE (-3225 2750);
FORCEPROP 1 LAST BODY_TYPE PLUMBING
J 0
(-3225 2800);
DISPLAY 0.872340 (-3225 2800);
PAINT GREEN (-3225 2800);
DISPLAY INVISIBLE (-3225 2800);
FORCEPROP 1 LAST HDL_TAP TRUE
J 0
(-2900 2625);
DISPLAY 0.872340 (-2900 2625);
DISPLAY INVISIBLE (-2900 2625);
FORCEPROP 1 LAST PATH I237
J 0
(-3227 2750);
DISPLAY 0.872340 (-3227 2750);
PAINT GREEN (-3227 2750);
DISPLAY INVISIBLE (-3227 2750);
FORCEADD SCONN288_DDR506112002KQ..2
(-4225 3600);
FORCEPROP 1 LAST LOCATION J24
J 0
(-4825 4925);
DISPLAY 0.468085 (-4825 4925);
PAINT SKYBLUE (-4825 4925);
FORCEPROP 0 LAST $SEC 2
J 0
(-4675 5075);
DISPLAY 0.680851 (-4675 5075);
PAINT MONO (-4675 5075);
DISPLAY INVISIBLE (-4675 5075);
FORCEPROP 2 LAST CDS_SEC 2
J 0
(-4675 5075);
DISPLAY 0.680851 (-4675 5075);
DISPLAY INVISIBLE (-4675 5075);
FORCEPROP 0 LASTPIN (-3475 3650) $PN 12
J 0
(-3465 3660);
DISPLAY 0.680851 (-3465 3660);
PAINT MONO (-3465 3660);
FORCEPROP 0 LASTPIN (-3475 3700) $PN 11
J 0
(-3465 3710);
DISPLAY 0.680851 (-3465 3710);
PAINT MONO (-3465 3710);
FORCEPROP 0 LASTPIN (-3475 2600) $PN 105
J 0
(-3465 2610);
DISPLAY 0.680851 (-3465 2610);
PAINT MONO (-3465 2610);
FORCEPROP 0 LASTPIN (-3475 2650) $PN 104
J 0
(-3465 2660);
DISPLAY 0.680851 (-3465 2660);
PAINT MONO (-3465 2660);
FORCEPROP 0 LASTPIN (-3475 3750) $PN 23
J 0
(-3465 3760);
DISPLAY 0.680851 (-3465 3760);
PAINT MONO (-3465 3760);
FORCEPROP 0 LASTPIN (-3475 3800) $PN 22
J 0
(-3465 3810);
DISPLAY 0.680851 (-3465 3810);
PAINT MONO (-3465 3810);
FORCEPROP 0 LASTPIN (-3475 2700) $PN 116
J 0
(-3465 2710);
DISPLAY 0.680851 (-3465 2710);
PAINT MONO (-3465 2710);
FORCEPROP 0 LASTPIN (-3475 2750) $PN 115
J 0
(-3465 2760);
DISPLAY 0.680851 (-3465 2760);
PAINT MONO (-3465 2760);
FORCEPROP 0 LASTPIN (-3475 3850) $PN 34
J 0
(-3465 3860);
DISPLAY 0.680851 (-3465 3860);
PAINT MONO (-3465 3860);
FORCEPROP 0 LASTPIN (-3475 3900) $PN 33
J 0
(-3465 3910);
DISPLAY 0.680851 (-3465 3910);
PAINT MONO (-3465 3910);
FORCEPROP 0 LASTPIN (-3475 2800) $PN 127
J 0
(-3465 2810);
DISPLAY 0.680851 (-3465 2810);
PAINT MONO (-3465 2810);
FORCEPROP 0 LASTPIN (-3475 2850) $PN 126
J 0
(-3465 2860);
DISPLAY 0.680851 (-3465 2860);
PAINT MONO (-3465 2860);
FORCEPROP 0 LASTPIN (-3475 3950) $PN 45
J 0
(-3465 3960);
DISPLAY 0.680851 (-3465 3960);
PAINT MONO (-3465 3960);
FORCEPROP 0 LASTPIN (-3475 4000) $PN 44
J 0
(-3465 4010);
DISPLAY 0.680851 (-3465 4010);
PAINT MONO (-3465 4010);
FORCEPROP 0 LASTPIN (-3475 2900) $PN 138
J 0
(-3465 2910);
DISPLAY 0.680851 (-3465 2910);
PAINT MONO (-3465 2910);
FORCEPROP 0 LASTPIN (-3475 2950) $PN 137
J 0
(-3465 2960);
DISPLAY 0.680851 (-3465 2960);
PAINT MONO (-3465 2960);
FORCEPROP 0 LASTPIN (-3475 4050) $PN 56
J 0
(-3465 4060);
DISPLAY 0.680851 (-3465 4060);
PAINT MONO (-3465 4060);
FORCEPROP 0 LASTPIN (-3475 4100) $PN 55
J 0
(-3465 4110);
DISPLAY 0.680851 (-3465 4110);
PAINT MONO (-3465 4110);
FORCEPROP 0 LASTPIN (-3475 3000) $PN 238
J 0
(-3465 3010);
DISPLAY 0.680851 (-3465 3010);
PAINT MONO (-3465 3010);
FORCEPROP 0 LASTPIN (-3475 3050) $PN 239
J 0
(-3465 3060);
DISPLAY 0.680851 (-3465 3060);
PAINT MONO (-3465 3060);
FORCEPROP 0 LASTPIN (-3475 4150) $PN 156
J 0
(-3465 4160);
DISPLAY 0.680851 (-3465 4160);
PAINT MONO (-3465 4160);
FORCEPROP 0 LASTPIN (-3475 4200) $PN 157
J 0
(-3465 4210);
DISPLAY 0.680851 (-3465 4210);
PAINT MONO (-3465 4210);
FORCEPROP 0 LASTPIN (-3475 3100) $PN 249
J 0
(-3465 3110);
DISPLAY 0.680851 (-3465 3110);
PAINT MONO (-3465 3110);
FORCEPROP 0 LASTPIN (-3475 3150) $PN 250
J 0
(-3465 3160);
DISPLAY 0.680851 (-3465 3160);
PAINT MONO (-3465 3160);
FORCEPROP 0 LASTPIN (-3475 4250) $PN 167
J 0
(-3465 4260);
DISPLAY 0.680851 (-3465 4260);
PAINT MONO (-3465 4260);
FORCEPROP 0 LASTPIN (-3475 4300) $PN 168
J 0
(-3465 4310);
DISPLAY 0.680851 (-3465 4310);
PAINT MONO (-3465 4310);
FORCEPROP 0 LASTPIN (-3475 3200) $PN 260
J 0
(-3465 3210);
DISPLAY 0.680851 (-3465 3210);
PAINT MONO (-3465 3210);
FORCEPROP 0 LASTPIN (-3475 3250) $PN 261
J 0
(-3465 3260);
DISPLAY 0.680851 (-3465 3260);
PAINT MONO (-3465 3260);
FORCEPROP 0 LASTPIN (-3475 4350) $PN 178
J 0
(-3465 4360);
DISPLAY 0.680851 (-3465 4360);
PAINT MONO (-3465 4360);
FORCEPROP 0 LASTPIN (-3475 4400) $PN 179
J 0
(-3465 4410);
DISPLAY 0.680851 (-3465 4410);
PAINT MONO (-3465 4410);
FORCEPROP 0 LASTPIN (-3475 3300) $PN 271
J 0
(-3465 3310);
DISPLAY 0.680851 (-3465 3310);
PAINT MONO (-3465 3310);
FORCEPROP 0 LASTPIN (-3475 3350) $PN 272
J 0
(-3465 3360);
DISPLAY 0.680851 (-3465 3360);
PAINT MONO (-3465 3360);
FORCEPROP 0 LASTPIN (-3475 4450) $PN 189
J 0
(-3465 4460);
DISPLAY 0.680851 (-3465 4460);
PAINT MONO (-3465 4460);
FORCEPROP 0 LASTPIN (-3475 4500) $PN 190
J 0
(-3465 4510);
DISPLAY 0.680851 (-3465 4510);
PAINT MONO (-3465 4510);
FORCEPROP 0 LASTPIN (-3475 3400) $PN 282
J 0
(-3465 3410);
DISPLAY 0.680851 (-3465 3410);
PAINT MONO (-3465 3410);
FORCEPROP 0 LASTPIN (-3475 3450) $PN 283
J 0
(-3465 3460);
DISPLAY 0.680851 (-3465 3460);
PAINT MONO (-3465 3460);
FORCEPROP 0 LASTPIN (-3475 4550) $PN 200
J 0
(-3465 4560);
DISPLAY 0.680851 (-3465 4560);
PAINT MONO (-3465 4560);
FORCEPROP 0 LASTPIN (-3475 4600) $PN 201
J 0
(-3465 4610);
DISPLAY 0.680851 (-3465 4610);
PAINT MONO (-3465 4610);
FORCEPROP 0 LASTPIN (-3475 3500) $PN 94
J 0
(-3465 3510);
DISPLAY 0.680851 (-3465 3510);
PAINT MONO (-3465 3510);
FORCEPROP 0 LASTPIN (-3475 3550) $PN 93
J 0
(-3465 3560);
DISPLAY 0.680851 (-3465 3560);
PAINT MONO (-3465 3560);
FORCEPROP 2 LAST PART_TYPE SMLF
J 0
(-4675 5025);
DISPLAY 1.021277 (-4675 5025);
FORCEPROP 1 LAST MATERIAL IO
J 0
(-4825 4775);
DISPLAY 0.468085 (-4825 4775);
PAINT SKYBLUE (-4825 4775);
FORCEPROP 2 LAST VALUE SCONN288_DDR506112002KQ
J 0
(-4675 4975);
DISPLAY 0.489362 (-4675 4975);
PAINT SKYBLUE (-4675 4975);
FORCEPROP 1 LAST CDS_LMAN_SYM_OUTLINE -600,1150,600,-1150
J 0
(-4225 3600);
DISPLAY 0.468085 (-4225 3600);
PAINT GREEN (-4225 3600);
DISPLAY INVISIBLE (-4225 3600);
FORCEPROP 1 LAST NEEDS_NO_SIZE TRUE
J 0
(-4225 3600);
DISPLAY 0.723404 (-4225 3600);
PAINT GREEN (-4225 3600);
DISPLAY INVISIBLE (-4225 3600);
FORCEPROP 2 LAST CDS_LIB pure_quanta
J 0
(-4225 3600);
DISPLAY INVISIBLE (-4225 3600);
FORCEPROP 1 LAST PATH I238
J 0
(-4225 3600);
DISPLAY 0.723404 (-4225 3600);
PAINT GREEN (-4225 3600);
DISPLAY INVISIBLE (-4225 3600);
FORCEPROP 1 LAST PART_NUMBER DFHST8FS479
J 0
(-4825 4850);
DISPLAY 0.468085 (-4825 4850);
PAINT SKYBLUE (-4825 4850);
DISPLAY INVISIBLE (-4825 4850);
FORCEADD GND..1
(-2800 5750);
FORCEPROP 3 LASTPIN (-2800 5800) SIG_NAME GND\g
J 0
(-2790 5810);
DISPLAY 0.659574 (-2790 5810);
PAINT MONO (-2790 5810);
DISPLAY INVISIBLE (-2790 5810);
FORCEPROP 2 LAST CDS_LIB pure_quanta_power
J 0
(-2800 5750);
DISPLAY INVISIBLE (-2800 5750);
FORCEPROP 2 LAST BOM_COST MEM
J 0
(-2775 5875);
DISPLAY 0.659574 (-2775 5875);
DISPLAY INVISIBLE (-2775 5875);
FORCEPROP 1 LAST SIZE 1B
J 0
(-2725 5700);
DISPLAY 0.723404 (-2725 5700);
PAINT GREEN (-2725 5700);
DISPLAY INVISIBLE (-2725 5700);
FORCEPROP 2 LAST ROOM MEM_EFGH_DECOUPLING_CAPS
J 0
(-2775 5825);
DISPLAY 0.659574 (-2775 5825);
PAINT RED (-2775 5825);
DISPLAY INVISIBLE (-2775 5825);
FORCEPROP 1 LAST HDL_POWER GND
J 0
(-2800 5900);
DISPLAY 0.723404 (-2800 5900);
PAINT GREEN (-2800 5900);
DISPLAY INVISIBLE (-2800 5900);
FORCEPROP 1 LAST PATH I239
J 0
(-2725 5750);
DISPLAY 0.872340 (-2725 5750);
PAINT AQUA (-2725 5750);
DISPLAY INVISIBLE (-2725 5750);
FORCEADD TAP..1
R 2
(-7450 3325);
FORCEPROP 3 LASTPIN (-7400 3325) SIG_NAME M_A_CPU1_SB_CB<1>
J 0
(-7390 3335);
DISPLAY 0.659574 (-7390 3335);
PAINT MONO (-7390 3335);
DISPLAY INVISIBLE (-7390 3335);
FORCEPROP 1 LASTPIN (-7400 3325) BN 1
J 2
(-7388 3333);
DISPLAY 0.489362 (-7388 3333);
PAINT GREEN (-7388 3333);
FORCEPROP 2 LAST CDS_LIB mstr_standard
J 0
(-7450 3325);
DISPLAY 0.723404 (-7450 3325);
PAINT MONO (-7450 3325);
DISPLAY INVISIBLE (-7450 3325);
FORCEPROP 1 LAST BODY_TYPE PLUMBING
J 2
(-7450 3375);
DISPLAY 0.872340 (-7450 3375);
PAINT GREEN (-7450 3375);
DISPLAY INVISIBLE (-7450 3375);
FORCEPROP 1 LAST HDL_TAP TRUE
J 2
(-7775 3200);
DISPLAY 0.872340 (-7775 3200);
DISPLAY INVISIBLE (-7775 3200);
FORCEPROP 1 LAST PATH I24
J 2
(-7448 3325);
DISPLAY 0.872340 (-7448 3325);
PAINT GREEN (-7448 3325);
DISPLAY INVISIBLE (-7448 3325);
FORCEADD Q_CAP..1
R 2
(-2800 6100);
FORCEPROP 1 LAST LOCATION C173
J 2
(-2850 6200);
DISPLAY 0.489362 (-2850 6200);
PAINT SKYBLUE (-2850 6200);
FORCEPROP 0 LAST $SEC 1
J 0
(-2850 6250);
DISPLAY 0.680851 (-2850 6250);
PAINT MONO (-2850 6250);
DISPLAY INVISIBLE (-2850 6250);
FORCEPROP 0 LAST CDS_SEC 1
J 0
(-2850 6250);
DISPLAY 0.680851 (-2850 6250);
DISPLAY INVISIBLE (-2850 6250);
FORCEPROP 1 LASTPIN (-2800 6200) $PN 1
J 2
(-2810 6180);
DISPLAY 0.489362 (-2810 6180);
PAINT MONO (-2810 6180);
FORCEPROP 1 LASTPIN (-2800 6000) $PN 2
J 2
(-2810 5980);
DISPLAY 0.489362 (-2810 5980);
PAINT MONO (-2810 5980);
FORCEPROP 1 LAST PACK_TYPE C0805
J 2
(-2850 5900);
DISPLAY 0.489362 (-2850 5900);
PAINT SKYBLUE (-2850 5900);
FORCEPROP 1 LAST VOLTAGE 25V
J 2
(-2850 6100);
DISPLAY 0.489362 (-2850 6100);
PAINT SKYBLUE (-2850 6100);
FORCEPROP 1 LAST VALUE 10UF
J 2
(-2850 6150);
DISPLAY 0.489362 (-2850 6150);
PAINT SKYBLUE (-2850 6150);
FORCEPROP 1 LAST TOLERANCE 10%
J 2
(-2850 6050);
DISPLAY 0.489362 (-2850 6050);
PAINT SKYBLUE (-2850 6050);
FORCEPROP 1 LAST MATERIAL X6S
J 2
(-2850 6000);
DISPLAY 0.489362 (-2850 6000);
PAINT SKYBLUE (-2850 6000);
FORCEPROP 2 LAST CDS_LIB pure_quanta
J 0
(-2800 6100);
DISPLAY INVISIBLE (-2800 6100);
FORCEPROP 0 LAST BOM_COST MEM
J 2
(-2855 6245);
DISPLAY 0.595745 (-2855 6245);
PAINT MONO (-2855 6245);
DISPLAY INVISIBLE (-2855 6245);
FORCEPROP 2 LAST ROOM 
J 2
(-2855 6245);
DISPLAY 0.595745 (-2855 6245);
PAINT RED (-2855 6245);
DISPLAY INVISIBLE (-2855 6245);
FORCEPROP 1 LAST PATH I240
J 2
(-2850 6250);
DISPLAY 0.978723 (-2850 6250);
PAINT WHITE (-2850 6250);
DISPLAY INVISIBLE (-2850 6250);
FORCEPROP 1 LAST PART_NUMBER CH6104KEA00
J 2
(-2850 5950);
DISPLAY 0.489362 (-2850 5950);
PAINT SKYBLUE (-2850 5950);
DISPLAY INVISIBLE (-2850 5950);
FORCEADD Q_CAP..1
R 2
(-2225 6100);
FORCEPROP 1 LAST LOCATION C174
J 2
(-2275 6200);
DISPLAY 0.489362 (-2275 6200);
PAINT SKYBLUE (-2275 6200);
FORCEPROP 0 LAST $SEC 1
J 0
(-2275 6250);
DISPLAY 0.680851 (-2275 6250);
PAINT MONO (-2275 6250);
DISPLAY INVISIBLE (-2275 6250);
FORCEPROP 0 LAST CDS_SEC 1
J 0
(-2275 6250);
DISPLAY 0.680851 (-2275 6250);
DISPLAY INVISIBLE (-2275 6250);
FORCEPROP 1 LASTPIN (-2225 6200) $PN 1
J 2
(-2235 6180);
DISPLAY 0.489362 (-2235 6180);
PAINT MONO (-2235 6180);
FORCEPROP 1 LASTPIN (-2225 6000) $PN 2
J 2
(-2235 5980);
DISPLAY 0.489362 (-2235 5980);
PAINT MONO (-2235 5980);
FORCEPROP 1 LAST PACK_TYPE C0805
J 2
(-2275 5900);
DISPLAY 0.489362 (-2275 5900);
PAINT SKYBLUE (-2275 5900);
FORCEPROP 1 LAST VOLTAGE 25V
J 2
(-2275 6100);
DISPLAY 0.489362 (-2275 6100);
PAINT SKYBLUE (-2275 6100);
FORCEPROP 1 LAST VALUE 10UF
J 2
(-2275 6150);
DISPLAY 0.489362 (-2275 6150);
PAINT SKYBLUE (-2275 6150);
FORCEPROP 1 LAST TOLERANCE 10%
J 2
(-2275 6050);
DISPLAY 0.489362 (-2275 6050);
PAINT SKYBLUE (-2275 6050);
FORCEPROP 1 LAST MATERIAL X6S
J 2
(-2275 6000);
DISPLAY 0.489362 (-2275 6000);
PAINT SKYBLUE (-2275 6000);
FORCEPROP 2 LAST CDS_LIB pure_quanta
J 0
(-2225 6100);
DISPLAY INVISIBLE (-2225 6100);
FORCEPROP 0 LAST BOM_COST MEM
J 2
(-2280 6245);
DISPLAY 0.595745 (-2280 6245);
PAINT MONO (-2280 6245);
DISPLAY INVISIBLE (-2280 6245);
FORCEPROP 2 LAST ROOM 
J 2
(-2280 6245);
DISPLAY 0.595745 (-2280 6245);
PAINT RED (-2280 6245);
DISPLAY INVISIBLE (-2280 6245);
FORCEPROP 1 LAST PATH I241
J 2
(-2275 6250);
DISPLAY 0.978723 (-2275 6250);
PAINT WHITE (-2275 6250);
DISPLAY INVISIBLE (-2275 6250);
FORCEPROP 1 LAST PART_NUMBER CH6104KEA00
J 2
(-2275 5950);
DISPLAY 0.489362 (-2275 5950);
PAINT SKYBLUE (-2275 5950);
DISPLAY INVISIBLE (-2275 5950);
FORCEADD UNIVERSAL_POWER..1
(-2800 6425);
FORCEPROP 3 LASTPIN (-2800 6375) SIG_NAME P12V_MEM_CPU1\g
J 0
(-2790 6385);
DISPLAY 0.659574 (-2790 6385);
PAINT MONO (-2790 6385);
DISPLAY INVISIBLE (-2790 6385);
FORCEPROP 1 LAST HDL_POWER P12V_MEM_CPU1
J 1
(-2800 6475);
DISPLAY 0.489362 (-2800 6475);
PAINT GREEN (-2800 6475);
FORCEPROP 2 LAST CDS_LIB pure_quanta_power
J 0
(-2800 6425);
DISPLAY INVISIBLE (-2800 6425);
FORCEPROP 1 LAST PATH I242
J 0
(-2750 6450);
DISPLAY 0.872340 (-2750 6450);
PAINT AQUA (-2750 6450);
DISPLAY INVISIBLE (-2750 6450);
FORCEADD OFFPAGE..1
(-8100 2725);
FORCEPROP 2 LAST $XR5 103 
J 0
(-8922 2725);
DISPLAY 0.638298 (-8922 2725);
PAINT MONO (-8922 2725);
FORCEPROP 2 LAST $XR4 102 
J 0
(-8802 2725);
DISPLAY 0.638298 (-8802 2725);
PAINT MONO (-8802 2725);
FORCEPROP 2 LAST $XR3 101 
J 0
(-8682 2725);
DISPLAY 0.638298 (-8682 2725);
PAINT MONO (-8682 2725);
FORCEPROP 2 LAST $XR2 100 
J 0
(-8562 2725);
DISPLAY 0.638298 (-8562 2725);
PAINT MONO (-8562 2725);
FORCEPROP 2 LAST $XR1 99 
J 0
(-8442 2725);
DISPLAY 0.638298 (-8442 2725);
PAINT MONO (-8442 2725);
FORCEPROP 2 LAST $XR0 159 
J 0
(-8352 2725);
DISPLAY 0.638298 (-8352 2725);
PAINT MONO (-8352 2725);
FORCEPROP 2 LAST CDS_LIB mstr_standard
J 0
(-8100 2725);
DISPLAY 0.808511 (-8100 2725);
DISPLAY INVISIBLE (-8100 2725);
FORCEPROP 1 LAST OFFPAGE TRUE
J 0
(-7775 2600);
DISPLAY 0.872340 (-7775 2600);
PAINT GREEN (-7775 2600);
DISPLAY INVISIBLE (-7775 2600);
FORCEPROP 1 LAST COMMENT_BODY TRUE
J 0
(-7975 2625);
DISPLAY 0.872340 (-7975 2625);
PAINT GREEN (-7975 2625);
DISPLAY INVISIBLE (-7975 2625);
FORCEPROP 2 LAST PATH I243
J 0
(-8400 2775);
DISPLAY 0.680851 (-8400 2775);
DISPLAY INVISIBLE (-8400 2775);
FORCEADD Q_RES..1
(-7475 2725);
FORCEPROP 1 LAST LOCATION R1580
J 0
(-7525 2750);
DISPLAY 0.510638 (-7525 2750);
PAINT SKYBLUE (-7525 2750);
FORCEPROP 0 LAST $SEC 1
J 0
(-7525 2825);
DISPLAY 0.680851 (-7525 2825);
PAINT MONO (-7525 2825);
DISPLAY INVISIBLE (-7525 2825);
FORCEPROP 0 LAST CDS_SEC 1
J 0
(-7525 2825);
DISPLAY 0.680851 (-7525 2825);
DISPLAY INVISIBLE (-7525 2825);
FORCEPROP 1 LASTPIN (-7575 2725) $PN 1
J 0
(-7563 2737);
DISPLAY 0.787234 (-7563 2737);
PAINT MONO (-7563 2737);
FORCEPROP 1 LASTPIN (-7375 2725) $PN 2
J 0
(-7413 2737);
DISPLAY 0.787234 (-7413 2737);
PAINT MONO (-7413 2737);
FORCEPROP 1 LAST VALUE 49.9
J 2
(-7325 2775);
DISPLAY 0.510638 (-7325 2775);
PAINT SKYBLUE (-7325 2775);
FORCEPROP 2 LAST CDS_LIB pure_quanta
J 0
(-7475 2725);
DISPLAY INVISIBLE (-7475 2725);
FORCEPROP 1 LAST TOLERANCE 1%
J 0
(-7475 2625);
DISPLAY 0.978723 (-7475 2625);
DISPLAY INVISIBLE (-7475 2625);
FORCEPROP 1 LAST WATTAGE 1/16W
J 2
(-7500 2575);
DISPLAY 0.978723 (-7500 2575);
DISPLAY INVISIBLE (-7500 2575);
FORCEPROP 1 LAST PACK_TYPE 0402LF
J 0
(-7225 2575);
DISPLAY 0.978723 (-7225 2575);
DISPLAY INVISIBLE (-7225 2575);
FORCEPROP 1 LAST MATERIAL CHIP
J 0
(-7475 2575);
DISPLAY 0.978723 (-7475 2575);
DISPLAY INVISIBLE (-7475 2575);
FORCEPROP 1 LAST PATH I244
J 0
(-7525 2875);
DISPLAY 0.978723 (-7525 2875);
PAINT WHITE (-7525 2875);
DISPLAY INVISIBLE (-7525 2875);
FORCEPROP 1 LAST PART_NUMBER CS04992FB07
J 0
(-7525 2825);
DISPLAY 0.978723 (-7525 2825);
DISPLAY INVISIBLE (-7525 2825);
FORCEADD Q_RES..2
(-8950 1450);
FORCEPROP 1 LAST LOCATION R8039
J 0
(-8905 1575);
DISPLAY 0.978723 (-8905 1575);
FORCEPROP 0 LAST $SEC 1
J 0
(-8900 1625);
DISPLAY 0.680851 (-8900 1625);
PAINT MONO (-8900 1625);
DISPLAY INVISIBLE (-8900 1625);
FORCEPROP 0 LAST CDS_SEC 1
J 0
(-8900 1625);
DISPLAY 0.680851 (-8900 1625);
DISPLAY INVISIBLE (-8900 1625);
FORCEPROP 1 LASTPIN (-8950 1550) $PN 1
J 0
(-8945 1512);
DISPLAY 0.787234 (-8945 1512);
PAINT MONO (-8945 1512);
FORCEPROP 1 LASTPIN (-8950 1350) $PN 2
J 0
(-8945 1360);
DISPLAY 0.787234 (-8945 1360);
PAINT MONO (-8945 1360);
FORCEPROP 1 LAST TOLERANCE 1%
J 0
(-8905 1475);
DISPLAY 0.978723 (-8905 1475);
FORCEPROP 1 LAST WATTAGE 1/16W
J 0
(-8910 1425);
DISPLAY 0.978723 (-8910 1425);
FORCEPROP 1 LAST VALUE 10K
J 0
(-8905 1525);
DISPLAY 0.978723 (-8905 1525);
FORCEPROP 1 LAST MATERIAL CHIP
J 0
(-8910 1375);
DISPLAY 0.978723 (-8910 1375);
FORCEPROP 1 LAST PACK_TYPE 0402LF
J 0
(-8910 1275);
DISPLAY 0.978723 (-8910 1275);
FORCEPROP 2 LAST CDS_LIB pure_quanta
J 0
(-8950 1450);
DISPLAY INVISIBLE (-8950 1450);
FORCEPROP 1 LAST PATH I245
J 0
(-8900 1625);
DISPLAY 0.978723 (-8900 1625);
PAINT WHITE (-8900 1625);
DISPLAY INVISIBLE (-8900 1625);
FORCEPROP 1 LAST PART_NUMBER CS31002FB08
J 0
(-8910 1325);
DISPLAY 0.978723 (-8910 1325);
DISPLAY INVISIBLE (-8910 1325);
FORCEADD VCC_CORE..1
(-8950 1750);
FORCEPROP 3 LASTPIN (-8950 1700) SIG_NAME P3V3_AUX\g
J 0
(-8940 1710);
DISPLAY 0.659574 (-8940 1710);
PAINT MONO (-8940 1710);
DISPLAY INVISIBLE (-8940 1710);
FORCEPROP 1 LAST HDL_POWER P3V3_AUX
J 1
(-8950 1800);
DISPLAY 0.489362 (-8950 1800);
PAINT GREEN (-8950 1800);
FORCEPROP 2 LAST CDS_LIB pure_quanta_power
J 0
(-8950 1750);
DISPLAY INVISIBLE (-8950 1750);
FORCEPROP 2 LAST ROOM PVCCINFAON_CPU0_CTRL
J 0
(-8950 1850);
DISPLAY 0.808511 (-8950 1850);
PAINT RED (-8950 1850);
DISPLAY INVISIBLE (-8950 1850);
FORCEPROP 0 LAST VOLTAGE 3.3
J 0
(-9225 1900);
DISPLAY 1.021277 (-9225 1900);
PAINT SKYBLUE (-9225 1900);
DISPLAY INVISIBLE (-9225 1900);
FORCEPROP 1 LAST PATH I246
J 0
(-8900 1775);
DISPLAY 0.872340 (-8900 1775);
PAINT AQUA (-8900 1775);
DISPLAY INVISIBLE (-8900 1775);
FORCEADD OFFPAGE..2
(-7925 1050);
FORCEPROP 2 LAST $XR5 103 
J 0
(-7196 1050);
DISPLAY 0.638298 (-7196 1050);
PAINT MONO (-7196 1050);
FORCEPROP 2 LAST $XR4 102 
J 0
(-7316 1050);
DISPLAY 0.638298 (-7316 1050);
PAINT MONO (-7316 1050);
FORCEPROP 2 LAST $XR3 101 
J 0
(-7436 1050);
DISPLAY 0.638298 (-7436 1050);
PAINT MONO (-7436 1050);
FORCEPROP 2 LAST $XR2 100 
J 0
(-7556 1050);
DISPLAY 0.638298 (-7556 1050);
PAINT MONO (-7556 1050);
FORCEPROP 2 LAST $XR1 99 
J 0
(-7646 1050);
DISPLAY 0.638298 (-7646 1050);
PAINT MONO (-7646 1050);
FORCEPROP 2 LAST $XR0 98 
J 0
(-7736 1050);
DISPLAY 0.638298 (-7736 1050);
PAINT MONO (-7736 1050);
FORCEPROP 2 LAST CDS_LIB standard
J 0
(-7925 1050);
DISPLAY INVISIBLE (-7925 1050);
FORCEPROP 1 LAST OFFPAGE TRUE
J 0
(-7600 925);
DISPLAY 0.723404 (-7600 925);
PAINT GREEN (-7600 925);
DISPLAY INVISIBLE (-7600 925);
FORCEPROP 1 LAST COMMENT_BODY TRUE
J 0
(-7970 955);
DISPLAY 0.872340 (-7970 955);
PAINT GREEN (-7970 955);
DISPLAY INVISIBLE (-7970 955);
FORCEPROP 2 LAST PATH I247
J 0
(-7750 1125);
DISPLAY 0.680851 (-7750 1125);
DISPLAY INVISIBLE (-7750 1125);
FORCEADD OFFPAGE..6
(-4900 925);
FORCEPROP 2 LAST $XR5 103 
J 0
(-5749 925);
DISPLAY 0.638298 (-5749 925);
PAINT MONO (-5749 925);
FORCEPROP 2 LAST $XR4 102 
J 0
(-5629 925);
DISPLAY 0.638298 (-5629 925);
PAINT MONO (-5629 925);
FORCEPROP 2 LAST $XR3 101 
J 0
(-5509 925);
DISPLAY 0.638298 (-5509 925);
PAINT MONO (-5509 925);
FORCEPROP 2 LAST $XR2 100 
J 0
(-5389 925);
DISPLAY 0.638298 (-5389 925);
PAINT MONO (-5389 925);
FORCEPROP 2 LAST $XR1 99 
J 0
(-5269 925);
DISPLAY 0.638298 (-5269 925);
PAINT MONO (-5269 925);
FORCEPROP 2 LAST $XR0 98 
J 0
(-5179 925);
DISPLAY 0.638298 (-5179 925);
PAINT MONO (-5179 925);
FORCEPROP 2 LAST CDS_LIB standard
J 0
(-4900 925);
DISPLAY INVISIBLE (-4900 925);
FORCEPROP 1 LAST OFFPAGE TRUE
J 0
(-4575 800);
DISPLAY 0.872340 (-4575 800);
PAINT GREEN (-4575 800);
DISPLAY INVISIBLE (-4575 800);
FORCEPROP 1 LAST COMMENT_BODY TRUE
J 0
(-4800 850);
DISPLAY 0.872340 (-4800 850);
PAINT GREEN (-4800 850);
DISPLAY INVISIBLE (-4800 850);
FORCEPROP 2 LAST PATH I248
J 0
(-4850 1000);
DISPLAY 0.680851 (-4850 1000);
DISPLAY INVISIBLE (-4850 1000);
FORCEADD VCC_CORE..1
(-5025 1600);
FORCEPROP 3 LASTPIN (-5025 1550) SIG_NAME P3V3_AUX\g
J 0
(-5015 1560);
DISPLAY 0.659574 (-5015 1560);
PAINT MONO (-5015 1560);
DISPLAY INVISIBLE (-5015 1560);
FORCEPROP 1 LAST HDL_POWER P3V3_AUX
J 1
(-5025 1650);
DISPLAY 0.489362 (-5025 1650);
PAINT GREEN (-5025 1650);
FORCEPROP 2 LAST CDS_LIB pure_quanta_power
J 0
(-5025 1600);
DISPLAY INVISIBLE (-5025 1600);
FORCEPROP 2 LAST ROOM PVCCINFAON_CPU0_CTRL
J 0
(-5025 1700);
DISPLAY 0.808511 (-5025 1700);
PAINT RED (-5025 1700);
DISPLAY INVISIBLE (-5025 1700);
FORCEPROP 0 LAST VOLTAGE 3.3
J 0
(-5300 1750);
DISPLAY 1.021277 (-5300 1750);
PAINT SKYBLUE (-5300 1750);
DISPLAY INVISIBLE (-5300 1750);
FORCEPROP 1 LAST PATH I249
J 0
(-4975 1625);
DISPLAY 0.872340 (-4975 1625);
PAINT AQUA (-4975 1625);
DISPLAY INVISIBLE (-4975 1625);
FORCEADD TAP..1
R 2
(-7450 3375);
FORCEPROP 3 LASTPIN (-7400 3375) SIG_NAME M_A_CPU1_SB_CB<2>
J 0
(-7390 3385);
DISPLAY 0.659574 (-7390 3385);
PAINT MONO (-7390 3385);
DISPLAY INVISIBLE (-7390 3385);
FORCEPROP 1 LASTPIN (-7400 3375) BN 2
J 2
(-7388 3383);
DISPLAY 0.489362 (-7388 3383);
PAINT GREEN (-7388 3383);
FORCEPROP 2 LAST CDS_LIB mstr_standard
J 0
(-7450 3375);
DISPLAY 0.723404 (-7450 3375);
PAINT MONO (-7450 3375);
DISPLAY INVISIBLE (-7450 3375);
FORCEPROP 1 LAST BODY_TYPE PLUMBING
J 2
(-7450 3425);
DISPLAY 0.872340 (-7450 3425);
PAINT GREEN (-7450 3425);
DISPLAY INVISIBLE (-7450 3425);
FORCEPROP 1 LAST HDL_TAP TRUE
J 2
(-7775 3250);
DISPLAY 0.872340 (-7775 3250);
DISPLAY INVISIBLE (-7775 3250);
FORCEPROP 1 LAST PATH I25
J 2
(-7448 3375);
DISPLAY 0.872340 (-7448 3375);
PAINT GREEN (-7448 3375);
DISPLAY INVISIBLE (-7448 3375);
FORCEADD Q_RES..1
(-4000 925);
FORCEPROP 1 LAST LOCATION R8086
J 0
(-4050 975);
DISPLAY 0.978723 (-4050 975);
FORCEPROP 0 LAST $SEC 1
J 0
(-4050 1025);
DISPLAY 0.680851 (-4050 1025);
PAINT MONO (-4050 1025);
DISPLAY INVISIBLE (-4050 1025);
FORCEPROP 0 LAST CDS_SEC 1
J 0
(-4050 1025);
DISPLAY 0.680851 (-4050 1025);
DISPLAY INVISIBLE (-4050 1025);
FORCEPROP 1 LASTPIN (-4100 925) $PN 1
J 0
(-4088 937);
DISPLAY 0.787234 (-4088 937);
PAINT MONO (-4088 937);
FORCEPROP 1 LASTPIN (-3900 925) $PN 2
J 0
(-3938 937);
DISPLAY 0.787234 (-3938 937);
PAINT MONO (-3938 937);
FORCEPROP 1 LAST VALUE 0
J 2
(-4025 825);
DISPLAY 0.978723 (-4025 825);
FORCEPROP 1 LAST TOLERANCE 5%
J 0
(-4000 825);
DISPLAY 0.978723 (-4000 825);
FORCEPROP 1 LAST MATERIAL CHIP
J 0
(-4000 775);
DISPLAY 0.978723 (-4000 775);
FORCEPROP 1 LAST PACK_TYPE 0402LF
J 0
(-3750 775);
DISPLAY 0.978723 (-3750 775);
FORCEPROP 1 LAST WATTAGE 1/16W
J 2
(-4025 775);
DISPLAY 0.978723 (-4025 775);
FORCEPROP 2 LAST CDS_LIB pure_quanta
J 0
(-4000 925);
DISPLAY INVISIBLE (-4000 925);
FORCEPROP 1 LAST PATH I250
J 0
(-4050 1075);
DISPLAY 0.978723 (-4050 1075);
PAINT WHITE (-4050 1075);
DISPLAY INVISIBLE (-4050 1075);
FORCEPROP 1 LAST PART_NUMBER CS00002JB13
J 0
(-4225 725);
DISPLAY 0.978723 (-4225 725);
DISPLAY INVISIBLE (-4225 725);
FORCEADD Q_RES..1
(-4425 1400);
FORCEPROP 1 LAST LOCATION R8088
J 0
(-4475 1450);
DISPLAY 0.978723 (-4475 1450);
FORCEPROP 0 LAST $SEC 1
J 0
(-4475 1575);
DISPLAY 0.680851 (-4475 1575);
PAINT MONO (-4475 1575);
DISPLAY INVISIBLE (-4475 1575);
FORCEPROP 0 LAST CDS_SEC 1
J 0
(-4475 1575);
DISPLAY 0.680851 (-4475 1575);
DISPLAY INVISIBLE (-4475 1575);
FORCEPROP 1 LASTPIN (-4525 1400) $PN 1
J 0
(-4513 1412);
DISPLAY 0.787234 (-4513 1412);
PAINT MONO (-4513 1412);
FORCEPROP 1 LASTPIN (-4325 1400) $PN 2
J 0
(-4363 1412);
DISPLAY 0.787234 (-4363 1412);
PAINT MONO (-4363 1412);
FORCEPROP 1 LAST MATERIAL EMPTY
J 0
(-4425 1250);
DISPLAY 0.978723 (-4425 1250);
PAINT RED (-4425 1250);
FORCEPROP 1 LAST PACK_TYPE 0402LF
J 0
(-4175 1250);
DISPLAY 0.978723 (-4175 1250);
FORCEPROP 1 LAST WATTAGE 1/16W
J 2
(-4450 1250);
DISPLAY 0.978723 (-4450 1250);
FORCEPROP 1 LAST VALUE 10K
J 2
(-4450 1300);
DISPLAY 0.978723 (-4450 1300);
FORCEPROP 1 LAST TOLERANCE 1%
J 0
(-4425 1300);
DISPLAY 0.978723 (-4425 1300);
FORCEPROP 2 LAST CDS_LIB pure_quanta
J 0
(-4425 1400);
DISPLAY INVISIBLE (-4425 1400);
FORCEPROP 1 LAST PATH I251
J 0
(-4475 1550);
DISPLAY 0.978723 (-4475 1550);
PAINT WHITE (-4475 1550);
DISPLAY INVISIBLE (-4475 1550);
FORCEPROP 1 LAST PART_NUMBER CS31002FB08
J 0
(-4475 1525);
DISPLAY 0.978723 (-4475 1525);
DISPLAY INVISIBLE (-4475 1525);
FORCEADD Q_RES..1
(-2575 925);
FORCEPROP 1 LAST LOCATION R8087
J 0
(-2625 975);
DISPLAY 0.978723 (-2625 975);
FORCEPROP 0 LAST $SEC 1
J 0
(-2625 1025);
DISPLAY 0.680851 (-2625 1025);
PAINT MONO (-2625 1025);
DISPLAY INVISIBLE (-2625 1025);
FORCEPROP 0 LAST CDS_SEC 1
J 0
(-2625 1025);
DISPLAY 0.680851 (-2625 1025);
DISPLAY INVISIBLE (-2625 1025);
FORCEPROP 1 LASTPIN (-2675 925) $PN 1
J 0
(-2663 937);
DISPLAY 0.787234 (-2663 937);
PAINT MONO (-2663 937);
FORCEPROP 1 LASTPIN (-2475 925) $PN 2
J 0
(-2513 937);
DISPLAY 0.787234 (-2513 937);
PAINT MONO (-2513 937);
FORCEPROP 1 LAST WATTAGE 1/16W
J 2
(-2600 775);
DISPLAY 0.978723 (-2600 775);
FORCEPROP 1 LAST MATERIAL CHIP
J 0
(-2575 775);
DISPLAY 0.978723 (-2575 775);
FORCEPROP 1 LAST PACK_TYPE 0402LF
J 0
(-2325 775);
DISPLAY 0.978723 (-2325 775);
FORCEPROP 1 LAST TOLERANCE 5%
J 0
(-2575 825);
DISPLAY 0.978723 (-2575 825);
FORCEPROP 1 LAST VALUE 0
J 2
(-2600 825);
DISPLAY 0.978723 (-2600 825);
FORCEPROP 2 LAST CDS_LIB pure_quanta
J 0
(-2575 925);
DISPLAY INVISIBLE (-2575 925);
FORCEPROP 1 LAST PATH I252
J 0
(-2625 1075);
DISPLAY 0.978723 (-2625 1075);
PAINT WHITE (-2625 1075);
DISPLAY INVISIBLE (-2625 1075);
FORCEPROP 1 LAST PART_NUMBER CS00002JB13
J 0
(-2775 700);
DISPLAY 0.978723 (-2775 700);
DISPLAY INVISIBLE (-2775 700);
FORCEADD SCHOTTKY_12..1
(-2475 1375);
FORCEPROP 1 LAST LOCATION D8005
J 0
(-2550 1550);
DISPLAY 0.723404 (-2550 1550);
PAINT GREEN (-2550 1550);
FORCEPROP 0 LAST $SEC 1
J 0
(-2550 1700);
DISPLAY 0.680851 (-2550 1700);
PAINT MONO (-2550 1700);
DISPLAY INVISIBLE (-2550 1700);
FORCEPROP 0 LAST CDS_SEC 1
J 0
(-2550 1700);
DISPLAY 0.680851 (-2550 1700);
DISPLAY INVISIBLE (-2550 1700);
FORCEPROP 0 LASTPIN (-2600 1375) $PN 1
J 2
(-2610 1385);
DISPLAY 0.680851 (-2610 1385);
PAINT MONO (-2610 1385);
FORCEPROP 0 LASTPIN (-2350 1375) $PN 2
J 0
(-2340 1385);
DISPLAY 0.680851 (-2340 1385);
PAINT MONO (-2340 1385);
FORCEPROP 1 LAST MATERIAL EMPTY
J 0
(-2550 1450);
DISPLAY 0.723404 (-2550 1450);
PAINT RED (-2550 1450);
FORCEPROP 2 LAST VALUE B0530WS7F
J 0
(-2550 1600);
DISPLAY 0.680851 (-2550 1600);
FORCEPROP 2 LAST PART_TYPE SMLF
J 0
(-2550 1650);
DISPLAY 0.680851 (-2550 1650);
FORCEPROP 2 LAST CDS_LIB pure_quanta
J 0
(-2475 1375);
DISPLAY INVISIBLE (-2475 1375);
FORCEPROP 1 LAST CDS_LMAN_SYM_OUTLINE -75,50,75,-50
J 0
(-2475 1375);
DISPLAY 0.468085 (-2475 1375);
PAINT GREEN (-2475 1375);
DISPLAY INVISIBLE (-2475 1375);
FORCEPROP 1 LAST NEEDS_NO_SIZE TRUE
J 0
(-2400 1325);
DISPLAY 0.468085 (-2400 1325);
PAINT GREEN (-2400 1325);
DISPLAY INVISIBLE (-2400 1325);
FORCEPROP 1 LAST PATH I253
J 0
(-2475 1375);
DISPLAY 0.723404 (-2475 1375);
PAINT GREEN (-2475 1375);
DISPLAY INVISIBLE (-2475 1375);
FORCEPROP 1 LAST PART_NUMBER BC000530Z41
J 0
(-2550 1500);
DISPLAY 0.723404 (-2550 1500);
PAINT GREEN (-2550 1500);
DISPLAY INVISIBLE (-2550 1500);
FORCEADD VCC_CORE..1
(-1800 1500);
FORCEPROP 3 LASTPIN (-1800 1450) SIG_NAME P3V3_AUX\g
J 0
(-1790 1460);
DISPLAY 0.659574 (-1790 1460);
PAINT MONO (-1790 1460);
DISPLAY INVISIBLE (-1790 1460);
FORCEPROP 1 LAST HDL_POWER P3V3_AUX
J 1
(-1800 1550);
DISPLAY 0.489362 (-1800 1550);
PAINT GREEN (-1800 1550);
FORCEPROP 2 LAST CDS_LIB pure_quanta_power
J 0
(-1800 1500);
DISPLAY INVISIBLE (-1800 1500);
FORCEPROP 0 LAST VOLTAGE 3.3
J 0
(-2075 1650);
DISPLAY 1.021277 (-2075 1650);
PAINT SKYBLUE (-2075 1650);
DISPLAY INVISIBLE (-2075 1650);
FORCEPROP 2 LAST ROOM PVCCINFAON_CPU0_CTRL
J 0
(-1800 1600);
DISPLAY 0.808511 (-1800 1600);
PAINT RED (-1800 1600);
DISPLAY INVISIBLE (-1800 1600);
FORCEPROP 1 LAST PATH I254
J 0
(-1750 1525);
DISPLAY 0.872340 (-1750 1525);
PAINT AQUA (-1750 1525);
DISPLAY INVISIBLE (-1750 1525);
FORCEADD OFFPAGE..6
R 2
(-1375 925);
FORCEPROP 2 LAST $XR0 82 
J 0
(-1161 925);
DISPLAY 0.638298 (-1161 925);
PAINT MONO (-1161 925);
FORCEPROP 2 LAST CDS_LIB standard
J 0
(-1375 925);
DISPLAY INVISIBLE (-1375 925);
FORCEPROP 1 LAST OFFPAGE TRUE
J 2
(-1700 800);
DISPLAY 0.872340 (-1700 800);
PAINT GREEN (-1700 800);
DISPLAY INVISIBLE (-1700 800);
FORCEPROP 1 LAST COMMENT_BODY TRUE
J 2
(-1475 850);
DISPLAY 0.872340 (-1475 850);
PAINT GREEN (-1475 850);
DISPLAY INVISIBLE (-1475 850);
FORCEPROP 2 LAST PATH I255
J 0
(-1175 1000);
DISPLAY 0.680851 (-1175 1000);
DISPLAY INVISIBLE (-1175 1000);
FORCEADD Q_RES..1
(-7875 2925);
FORCEPROP 1 LAST LOCATION R1687
J 0
(-8050 2925);
DISPLAY 0.510638 (-8050 2925);
FORCEPROP 0 LAST $SEC 1
J 0
(-7725 2950);
DISPLAY 0.680851 (-7725 2950);
PAINT MONO (-7725 2950);
DISPLAY INVISIBLE (-7725 2950);
FORCEPROP 0 LAST CDS_SEC 1
J 0
(-7725 2950);
DISPLAY 0.680851 (-7725 2950);
DISPLAY INVISIBLE (-7725 2950);
FORCEPROP 1 LASTPIN (-7975 2925) $PN 1
J 0
(-7963 2937);
DISPLAY 0.787234 (-7963 2937);
PAINT MONO (-7963 2937);
FORCEPROP 1 LASTPIN (-7775 2925) $PN 2
J 0
(-7813 2937);
DISPLAY 0.787234 (-7813 2937);
PAINT MONO (-7813 2937);
FORCEPROP 1 LAST MATERIAL CHIP
J 0
(-7975 2900);
DISPLAY 0.404255 (-7975 2900);
FORCEPROP 1 LAST VALUE 10
J 2
(-7725 2925);
DISPLAY 0.404255 (-7725 2925);
FORCEPROP 1 LAST PACK_TYPE 0402LF
J 0
(-7825 2900);
DISPLAY 0.404255 (-7825 2900);
FORCEPROP 1 LAST WATTAGE 1/16W
J 2
(-7900 2775);
DISPLAY 0.978723 (-7900 2775);
DISPLAY INVISIBLE (-7900 2775);
FORCEPROP 1 LAST TOLERANCE 1%
J 0
(-7875 2825);
DISPLAY 0.978723 (-7875 2825);
DISPLAY INVISIBLE (-7875 2825);
FORCEPROP 2 LAST CDS_LIB pure_quanta
J 0
(-7875 2925);
DISPLAY INVISIBLE (-7875 2925);
FORCEPROP 1 LAST PATH I256
J 0
(-7925 3075);
DISPLAY 0.978723 (-7925 3075);
PAINT WHITE (-7925 3075);
DISPLAY INVISIBLE (-7925 3075);
FORCEPROP 1 LAST PART_NUMBER CS01002FB07
J 0
(-7925 3025);
DISPLAY 0.978723 (-7925 3025);
DISPLAY INVISIBLE (-7925 3025);
FORCEADD OFFPAGE..6
(-8550 2850);
FORCEPROP 2 LAST $XR5 159 
J 0
(-9399 2850);
DISPLAY 0.638298 (-9399 2850);
PAINT MONO (-9399 2850);
FORCEPROP 2 LAST $XR4 103 
J 0
(-9279 2850);
DISPLAY 0.638298 (-9279 2850);
PAINT MONO (-9279 2850);
FORCEPROP 2 LAST $XR3 102 
J 0
(-9159 2850);
DISPLAY 0.638298 (-9159 2850);
PAINT MONO (-9159 2850);
FORCEPROP 2 LAST $XR2 101 
J 0
(-9039 2850);
DISPLAY 0.638298 (-9039 2850);
PAINT MONO (-9039 2850);
FORCEPROP 2 LAST $XR1 100 
J 0
(-8919 2850);
DISPLAY 0.638298 (-8919 2850);
PAINT MONO (-8919 2850);
FORCEPROP 2 LAST $XR0 99 
J 0
(-8799 2850);
DISPLAY 0.638298 (-8799 2850);
PAINT MONO (-8799 2850);
FORCEPROP 2 LAST CDS_LIB mstr_standard
J 0
(-8550 2850);
DISPLAY 0.808511 (-8550 2850);
DISPLAY INVISIBLE (-8550 2850);
FORCEPROP 1 LAST OFFPAGE TRUE
J 0
(-8225 2725);
DISPLAY 0.872340 (-8225 2725);
PAINT GREEN (-8225 2725);
DISPLAY INVISIBLE (-8225 2725);
FORCEPROP 1 LAST COMMENT_BODY TRUE
J 0
(-8450 2775);
DISPLAY 0.872340 (-8450 2775);
PAINT GREEN (-8450 2775);
DISPLAY INVISIBLE (-8450 2775);
FORCEPROP 2 LAST PATH I257
J 0
(-8825 2900);
DISPLAY 0.680851 (-8825 2900);
DISPLAY INVISIBLE (-8825 2900);
FORCEADD TAP..1
R 2
(-7450 3425);
FORCEPROP 3 LASTPIN (-7400 3425) SIG_NAME M_A_CPU1_SB_CB<3>
J 0
(-7390 3435);
DISPLAY 0.659574 (-7390 3435);
PAINT MONO (-7390 3435);
DISPLAY INVISIBLE (-7390 3435);
FORCEPROP 1 LASTPIN (-7400 3425) BN 3
J 2
(-7388 3433);
DISPLAY 0.489362 (-7388 3433);
PAINT GREEN (-7388 3433);
FORCEPROP 2 LAST CDS_LIB mstr_standard
J 0
(-7450 3425);
DISPLAY 0.723404 (-7450 3425);
PAINT MONO (-7450 3425);
DISPLAY INVISIBLE (-7450 3425);
FORCEPROP 1 LAST BODY_TYPE PLUMBING
J 2
(-7450 3475);
DISPLAY 0.872340 (-7450 3475);
PAINT GREEN (-7450 3475);
DISPLAY INVISIBLE (-7450 3475);
FORCEPROP 1 LAST HDL_TAP TRUE
J 2
(-7775 3300);
DISPLAY 0.872340 (-7775 3300);
DISPLAY INVISIBLE (-7775 3300);
FORCEPROP 1 LAST PATH I26
J 2
(-7448 3425);
DISPLAY 0.872340 (-7448 3425);
PAINT GREEN (-7448 3425);
DISPLAY INVISIBLE (-7448 3425);
FORCEADD TAP..1
R 2
(-7450 3475);
FORCEPROP 3 LASTPIN (-7400 3475) SIG_NAME M_A_CPU1_SB_CB<4>
J 0
(-7390 3485);
DISPLAY 0.659574 (-7390 3485);
PAINT MONO (-7390 3485);
DISPLAY INVISIBLE (-7390 3485);
FORCEPROP 1 LASTPIN (-7400 3475) BN 4
J 2
(-7388 3483);
DISPLAY 0.489362 (-7388 3483);
PAINT GREEN (-7388 3483);
FORCEPROP 2 LAST CDS_LIB mstr_standard
J 0
(-7450 3475);
DISPLAY 0.723404 (-7450 3475);
PAINT MONO (-7450 3475);
DISPLAY INVISIBLE (-7450 3475);
FORCEPROP 1 LAST BODY_TYPE PLUMBING
J 2
(-7450 3525);
DISPLAY 0.872340 (-7450 3525);
PAINT GREEN (-7450 3525);
DISPLAY INVISIBLE (-7450 3525);
FORCEPROP 1 LAST HDL_TAP TRUE
J 2
(-7775 3350);
DISPLAY 0.872340 (-7775 3350);
DISPLAY INVISIBLE (-7775 3350);
FORCEPROP 1 LAST PATH I27
J 2
(-7448 3475);
DISPLAY 0.872340 (-7448 3475);
PAINT GREEN (-7448 3475);
DISPLAY INVISIBLE (-7448 3475);
FORCEADD TAP..1
R 2
(-7450 3525);
FORCEPROP 3 LASTPIN (-7400 3525) SIG_NAME M_A_CPU1_SB_CB<5>
J 0
(-7390 3535);
DISPLAY 0.659574 (-7390 3535);
PAINT MONO (-7390 3535);
DISPLAY INVISIBLE (-7390 3535);
FORCEPROP 1 LASTPIN (-7400 3525) BN 5
J 2
(-7388 3533);
DISPLAY 0.489362 (-7388 3533);
PAINT GREEN (-7388 3533);
FORCEPROP 2 LAST CDS_LIB mstr_standard
J 0
(-7450 3525);
DISPLAY 0.723404 (-7450 3525);
PAINT MONO (-7450 3525);
DISPLAY INVISIBLE (-7450 3525);
FORCEPROP 1 LAST BODY_TYPE PLUMBING
J 2
(-7450 3575);
DISPLAY 0.872340 (-7450 3575);
PAINT GREEN (-7450 3575);
DISPLAY INVISIBLE (-7450 3575);
FORCEPROP 1 LAST HDL_TAP TRUE
J 2
(-7775 3400);
DISPLAY 0.872340 (-7775 3400);
DISPLAY INVISIBLE (-7775 3400);
FORCEPROP 1 LAST PATH I28
J 2
(-7448 3525);
DISPLAY 0.872340 (-7448 3525);
PAINT GREEN (-7448 3525);
DISPLAY INVISIBLE (-7448 3525);
FORCEADD TAP..1
R 2
(-7450 3575);
FORCEPROP 3 LASTPIN (-7400 3575) SIG_NAME M_A_CPU1_SB_CB<6>
J 0
(-7390 3585);
DISPLAY 0.659574 (-7390 3585);
PAINT MONO (-7390 3585);
DISPLAY INVISIBLE (-7390 3585);
FORCEPROP 1 LASTPIN (-7400 3575) BN 6
J 2
(-7388 3583);
DISPLAY 0.489362 (-7388 3583);
PAINT GREEN (-7388 3583);
FORCEPROP 2 LAST CDS_LIB mstr_standard
J 0
(-7450 3575);
DISPLAY 0.723404 (-7450 3575);
PAINT MONO (-7450 3575);
DISPLAY INVISIBLE (-7450 3575);
FORCEPROP 1 LAST BODY_TYPE PLUMBING
J 2
(-7450 3625);
DISPLAY 0.872340 (-7450 3625);
PAINT GREEN (-7450 3625);
DISPLAY INVISIBLE (-7450 3625);
FORCEPROP 1 LAST HDL_TAP TRUE
J 2
(-7775 3450);
DISPLAY 0.872340 (-7775 3450);
DISPLAY INVISIBLE (-7775 3450);
FORCEPROP 1 LAST PATH I29
J 2
(-7448 3575);
DISPLAY 0.872340 (-7448 3575);
PAINT GREEN (-7448 3575);
DISPLAY INVISIBLE (-7448 3575);
FORCEADD TAP..1
R 2
(-7450 3625);
FORCEPROP 3 LASTPIN (-7400 3625) SIG_NAME M_A_CPU1_SB_CB<7>
J 0
(-7390 3635);
DISPLAY 0.659574 (-7390 3635);
PAINT MONO (-7390 3635);
DISPLAY INVISIBLE (-7390 3635);
FORCEPROP 1 LASTPIN (-7400 3625) BN 7
J 2
(-7388 3633);
DISPLAY 0.489362 (-7388 3633);
PAINT GREEN (-7388 3633);
FORCEPROP 2 LAST CDS_LIB mstr_standard
J 0
(-7450 3625);
DISPLAY 0.723404 (-7450 3625);
PAINT MONO (-7450 3625);
DISPLAY INVISIBLE (-7450 3625);
FORCEPROP 1 LAST BODY_TYPE PLUMBING
J 2
(-7450 3675);
DISPLAY 0.872340 (-7450 3675);
PAINT GREEN (-7450 3675);
DISPLAY INVISIBLE (-7450 3675);
FORCEPROP 1 LAST HDL_TAP TRUE
J 2
(-7775 3500);
DISPLAY 0.872340 (-7775 3500);
DISPLAY INVISIBLE (-7775 3500);
FORCEPROP 1 LAST PATH I30
J 2
(-7448 3625);
DISPLAY 0.872340 (-7448 3625);
PAINT GREEN (-7448 3625);
DISPLAY INVISIBLE (-7448 3625);
FORCEADD TAP..1
R 2
(-7450 3725);
FORCEPROP 3 LASTPIN (-7400 3725) SIG_NAME M_A_CPU1_SA_CB<0>
J 0
(-7390 3735);
DISPLAY 0.659574 (-7390 3735);
PAINT MONO (-7390 3735);
DISPLAY INVISIBLE (-7390 3735);
FORCEPROP 1 LASTPIN (-7400 3725) BN 0
J 2
(-7388 3733);
DISPLAY 0.489362 (-7388 3733);
PAINT GREEN (-7388 3733);
FORCEPROP 2 LAST CDS_LIB mstr_standard
J 0
(-7450 3725);
DISPLAY 0.723404 (-7450 3725);
PAINT MONO (-7450 3725);
DISPLAY INVISIBLE (-7450 3725);
FORCEPROP 1 LAST BODY_TYPE PLUMBING
J 2
(-7450 3775);
DISPLAY 0.872340 (-7450 3775);
PAINT GREEN (-7450 3775);
DISPLAY INVISIBLE (-7450 3775);
FORCEPROP 1 LAST HDL_TAP TRUE
J 2
(-7775 3600);
DISPLAY 0.872340 (-7775 3600);
DISPLAY INVISIBLE (-7775 3600);
FORCEPROP 1 LAST PATH I31
J 2
(-7448 3725);
DISPLAY 0.872340 (-7448 3725);
PAINT GREEN (-7448 3725);
DISPLAY INVISIBLE (-7448 3725);
FORCEADD TAP..1
R 2
(-7450 3775);
FORCEPROP 3 LASTPIN (-7400 3775) SIG_NAME M_A_CPU1_SA_CB<1>
J 0
(-7390 3785);
DISPLAY 0.659574 (-7390 3785);
PAINT MONO (-7390 3785);
DISPLAY INVISIBLE (-7390 3785);
FORCEPROP 1 LASTPIN (-7400 3775) BN 1
J 2
(-7388 3783);
DISPLAY 0.489362 (-7388 3783);
PAINT GREEN (-7388 3783);
FORCEPROP 2 LAST CDS_LIB mstr_standard
J 0
(-7450 3775);
DISPLAY 0.723404 (-7450 3775);
PAINT MONO (-7450 3775);
DISPLAY INVISIBLE (-7450 3775);
FORCEPROP 1 LAST BODY_TYPE PLUMBING
J 2
(-7450 3825);
DISPLAY 0.872340 (-7450 3825);
PAINT GREEN (-7450 3825);
DISPLAY INVISIBLE (-7450 3825);
FORCEPROP 1 LAST HDL_TAP TRUE
J 2
(-7775 3650);
DISPLAY 0.872340 (-7775 3650);
DISPLAY INVISIBLE (-7775 3650);
FORCEPROP 1 LAST PATH I32
J 2
(-7448 3775);
DISPLAY 0.872340 (-7448 3775);
PAINT GREEN (-7448 3775);
DISPLAY INVISIBLE (-7448 3775);
FORCEADD TAP..1
R 2
(-7450 3825);
FORCEPROP 3 LASTPIN (-7400 3825) SIG_NAME M_A_CPU1_SA_CB<2>
J 0
(-7390 3835);
DISPLAY 0.659574 (-7390 3835);
PAINT MONO (-7390 3835);
DISPLAY INVISIBLE (-7390 3835);
FORCEPROP 1 LASTPIN (-7400 3825) BN 2
J 2
(-7388 3833);
DISPLAY 0.489362 (-7388 3833);
PAINT GREEN (-7388 3833);
FORCEPROP 2 LAST CDS_LIB mstr_standard
J 0
(-7450 3825);
DISPLAY 0.723404 (-7450 3825);
PAINT MONO (-7450 3825);
DISPLAY INVISIBLE (-7450 3825);
FORCEPROP 1 LAST BODY_TYPE PLUMBING
J 2
(-7450 3875);
DISPLAY 0.872340 (-7450 3875);
PAINT GREEN (-7450 3875);
DISPLAY INVISIBLE (-7450 3875);
FORCEPROP 1 LAST HDL_TAP TRUE
J 2
(-7775 3700);
DISPLAY 0.872340 (-7775 3700);
DISPLAY INVISIBLE (-7775 3700);
FORCEPROP 1 LAST PATH I33
J 2
(-7448 3825);
DISPLAY 0.872340 (-7448 3825);
PAINT GREEN (-7448 3825);
DISPLAY INVISIBLE (-7448 3825);
FORCEADD TAP..1
R 2
(-7450 3875);
FORCEPROP 3 LASTPIN (-7400 3875) SIG_NAME M_A_CPU1_SA_CB<3>
J 0
(-7390 3885);
DISPLAY 0.659574 (-7390 3885);
PAINT MONO (-7390 3885);
DISPLAY INVISIBLE (-7390 3885);
FORCEPROP 1 LASTPIN (-7400 3875) BN 3
J 2
(-7388 3883);
DISPLAY 0.489362 (-7388 3883);
PAINT GREEN (-7388 3883);
FORCEPROP 2 LAST CDS_LIB mstr_standard
J 0
(-7450 3875);
DISPLAY 0.723404 (-7450 3875);
PAINT MONO (-7450 3875);
DISPLAY INVISIBLE (-7450 3875);
FORCEPROP 1 LAST BODY_TYPE PLUMBING
J 2
(-7450 3925);
DISPLAY 0.872340 (-7450 3925);
PAINT GREEN (-7450 3925);
DISPLAY INVISIBLE (-7450 3925);
FORCEPROP 1 LAST HDL_TAP TRUE
J 2
(-7775 3750);
DISPLAY 0.872340 (-7775 3750);
DISPLAY INVISIBLE (-7775 3750);
FORCEPROP 1 LAST PATH I34
J 2
(-7448 3875);
DISPLAY 0.872340 (-7448 3875);
PAINT GREEN (-7448 3875);
DISPLAY INVISIBLE (-7448 3875);
FORCEADD TAP..1
R 2
(-7450 3925);
FORCEPROP 3 LASTPIN (-7400 3925) SIG_NAME M_A_CPU1_SA_CB<4>
J 0
(-7390 3935);
DISPLAY 0.659574 (-7390 3935);
PAINT MONO (-7390 3935);
DISPLAY INVISIBLE (-7390 3935);
FORCEPROP 1 LASTPIN (-7400 3925) BN 4
J 2
(-7388 3933);
DISPLAY 0.489362 (-7388 3933);
PAINT GREEN (-7388 3933);
FORCEPROP 2 LAST CDS_LIB mstr_standard
J 0
(-7450 3925);
DISPLAY 0.723404 (-7450 3925);
PAINT MONO (-7450 3925);
DISPLAY INVISIBLE (-7450 3925);
FORCEPROP 1 LAST BODY_TYPE PLUMBING
J 2
(-7450 3975);
DISPLAY 0.872340 (-7450 3975);
PAINT GREEN (-7450 3975);
DISPLAY INVISIBLE (-7450 3975);
FORCEPROP 1 LAST HDL_TAP TRUE
J 2
(-7775 3800);
DISPLAY 0.872340 (-7775 3800);
DISPLAY INVISIBLE (-7775 3800);
FORCEPROP 1 LAST PATH I35
J 2
(-7448 3925);
DISPLAY 0.872340 (-7448 3925);
PAINT GREEN (-7448 3925);
DISPLAY INVISIBLE (-7448 3925);
FORCEADD TAP..1
R 2
(-7450 3975);
FORCEPROP 3 LASTPIN (-7400 3975) SIG_NAME M_A_CPU1_SA_CB<5>
J 0
(-7390 3985);
DISPLAY 0.659574 (-7390 3985);
PAINT MONO (-7390 3985);
DISPLAY INVISIBLE (-7390 3985);
FORCEPROP 1 LASTPIN (-7400 3975) BN 5
J 2
(-7388 3983);
DISPLAY 0.489362 (-7388 3983);
PAINT GREEN (-7388 3983);
FORCEPROP 2 LAST CDS_LIB mstr_standard
J 0
(-7450 3975);
DISPLAY 0.723404 (-7450 3975);
PAINT MONO (-7450 3975);
DISPLAY INVISIBLE (-7450 3975);
FORCEPROP 1 LAST BODY_TYPE PLUMBING
J 2
(-7450 4025);
DISPLAY 0.872340 (-7450 4025);
PAINT GREEN (-7450 4025);
DISPLAY INVISIBLE (-7450 4025);
FORCEPROP 1 LAST HDL_TAP TRUE
J 2
(-7775 3850);
DISPLAY 0.872340 (-7775 3850);
DISPLAY INVISIBLE (-7775 3850);
FORCEPROP 1 LAST PATH I36
J 2
(-7448 3975);
DISPLAY 0.872340 (-7448 3975);
PAINT GREEN (-7448 3975);
DISPLAY INVISIBLE (-7448 3975);
FORCEADD TAP..1
R 2
(-7450 4025);
FORCEPROP 3 LASTPIN (-7400 4025) SIG_NAME M_A_CPU1_SA_CB<6>
J 0
(-7390 4035);
DISPLAY 0.659574 (-7390 4035);
PAINT MONO (-7390 4035);
DISPLAY INVISIBLE (-7390 4035);
FORCEPROP 1 LASTPIN (-7400 4025) BN 6
J 2
(-7388 4033);
DISPLAY 0.489362 (-7388 4033);
PAINT GREEN (-7388 4033);
FORCEPROP 2 LAST CDS_LIB mstr_standard
J 0
(-7450 4025);
DISPLAY 0.723404 (-7450 4025);
PAINT MONO (-7450 4025);
DISPLAY INVISIBLE (-7450 4025);
FORCEPROP 1 LAST BODY_TYPE PLUMBING
J 2
(-7450 4075);
DISPLAY 0.872340 (-7450 4075);
PAINT GREEN (-7450 4075);
DISPLAY INVISIBLE (-7450 4075);
FORCEPROP 1 LAST HDL_TAP TRUE
J 2
(-7775 3900);
DISPLAY 0.872340 (-7775 3900);
DISPLAY INVISIBLE (-7775 3900);
FORCEPROP 1 LAST PATH I37
J 2
(-7448 4025);
DISPLAY 0.872340 (-7448 4025);
PAINT GREEN (-7448 4025);
DISPLAY INVISIBLE (-7448 4025);
FORCEADD TAP..1
R 2
(-7450 4075);
FORCEPROP 3 LASTPIN (-7400 4075) SIG_NAME M_A_CPU1_SA_CB<7>
J 0
(-7390 4085);
DISPLAY 0.659574 (-7390 4085);
PAINT MONO (-7390 4085);
DISPLAY INVISIBLE (-7390 4085);
FORCEPROP 1 LASTPIN (-7400 4075) BN 7
J 2
(-7388 4083);
DISPLAY 0.489362 (-7388 4083);
PAINT GREEN (-7388 4083);
FORCEPROP 2 LAST CDS_LIB mstr_standard
J 0
(-7450 4075);
DISPLAY 0.723404 (-7450 4075);
PAINT MONO (-7450 4075);
DISPLAY INVISIBLE (-7450 4075);
FORCEPROP 1 LAST BODY_TYPE PLUMBING
J 2
(-7450 4125);
DISPLAY 0.872340 (-7450 4125);
PAINT GREEN (-7450 4125);
DISPLAY INVISIBLE (-7450 4125);
FORCEPROP 1 LAST HDL_TAP TRUE
J 2
(-7775 3950);
DISPLAY 0.872340 (-7775 3950);
DISPLAY INVISIBLE (-7775 3950);
FORCEPROP 1 LAST PATH I38
J 2
(-7448 4075);
DISPLAY 0.872340 (-7448 4075);
PAINT GREEN (-7448 4075);
DISPLAY INVISIBLE (-7448 4075);
FORCEADD TAP..1
(-5750 2325);
FORCEPROP 3 LASTPIN (-5800 2325) SIG_NAME M_A_CPU1_SB_DQ<1>
J 0
(-5790 2335);
DISPLAY 0.659574 (-5790 2335);
PAINT MONO (-5790 2335);
DISPLAY INVISIBLE (-5790 2335);
FORCEPROP 1 LASTPIN (-5800 2325) BN 1
J 0
(-5812 2333);
DISPLAY 0.489362 (-5812 2333);
PAINT GREEN (-5812 2333);
FORCEPROP 2 LAST CDS_LIB mstr_standard
J 0
(-5750 2325);
DISPLAY 0.723404 (-5750 2325);
PAINT MONO (-5750 2325);
DISPLAY INVISIBLE (-5750 2325);
FORCEPROP 1 LAST BODY_TYPE PLUMBING
J 0
(-5750 2375);
DISPLAY 0.872340 (-5750 2375);
PAINT GREEN (-5750 2375);
DISPLAY INVISIBLE (-5750 2375);
FORCEPROP 1 LAST HDL_TAP TRUE
J 0
(-5425 2200);
DISPLAY 0.872340 (-5425 2200);
DISPLAY INVISIBLE (-5425 2200);
FORCEPROP 1 LAST PATH I46
J 0
(-5752 2325);
DISPLAY 0.872340 (-5752 2325);
PAINT GREEN (-5752 2325);
DISPLAY INVISIBLE (-5752 2325);
FORCEADD TAP..1
(-5750 2275);
FORCEPROP 3 LASTPIN (-5800 2275) SIG_NAME M_A_CPU1_SB_DQ<0>
J 0
(-5790 2285);
DISPLAY 0.659574 (-5790 2285);
PAINT MONO (-5790 2285);
DISPLAY INVISIBLE (-5790 2285);
FORCEPROP 1 LASTPIN (-5800 2275) BN 0
J 0
(-5812 2283);
DISPLAY 0.489362 (-5812 2283);
PAINT GREEN (-5812 2283);
FORCEPROP 2 LAST CDS_LIB mstr_standard
J 0
(-5750 2275);
DISPLAY 0.723404 (-5750 2275);
PAINT MONO (-5750 2275);
DISPLAY INVISIBLE (-5750 2275);
FORCEPROP 1 LAST BODY_TYPE PLUMBING
J 0
(-5750 2325);
DISPLAY 0.872340 (-5750 2325);
PAINT GREEN (-5750 2325);
DISPLAY INVISIBLE (-5750 2325);
FORCEPROP 1 LAST HDL_TAP TRUE
J 0
(-5425 2150);
DISPLAY 0.872340 (-5425 2150);
DISPLAY INVISIBLE (-5425 2150);
FORCEPROP 1 LAST PATH I47
J 0
(-5752 2275);
DISPLAY 0.872340 (-5752 2275);
PAINT GREEN (-5752 2275);
DISPLAY INVISIBLE (-5752 2275);
FORCEADD TAP..1
(-5750 2475);
FORCEPROP 3 LASTPIN (-5800 2475) SIG_NAME M_A_CPU1_SB_DQ<4>
J 0
(-5790 2485);
DISPLAY 0.659574 (-5790 2485);
PAINT MONO (-5790 2485);
DISPLAY INVISIBLE (-5790 2485);
FORCEPROP 1 LASTPIN (-5800 2475) BN 4
J 0
(-5812 2483);
DISPLAY 0.489362 (-5812 2483);
PAINT GREEN (-5812 2483);
FORCEPROP 2 LAST CDS_LIB mstr_standard
J 0
(-5750 2475);
DISPLAY 0.723404 (-5750 2475);
PAINT MONO (-5750 2475);
DISPLAY INVISIBLE (-5750 2475);
FORCEPROP 1 LAST BODY_TYPE PLUMBING
J 0
(-5750 2525);
DISPLAY 0.872340 (-5750 2525);
PAINT GREEN (-5750 2525);
DISPLAY INVISIBLE (-5750 2525);
FORCEPROP 1 LAST HDL_TAP TRUE
J 0
(-5425 2350);
DISPLAY 0.872340 (-5425 2350);
DISPLAY INVISIBLE (-5425 2350);
FORCEPROP 1 LAST PATH I48
J 0
(-5752 2475);
DISPLAY 0.872340 (-5752 2475);
PAINT GREEN (-5752 2475);
DISPLAY INVISIBLE (-5752 2475);
FORCEADD TAP..1
(-5750 2425);
FORCEPROP 3 LASTPIN (-5800 2425) SIG_NAME M_A_CPU1_SB_DQ<3>
J 0
(-5790 2435);
DISPLAY 0.659574 (-5790 2435);
PAINT MONO (-5790 2435);
DISPLAY INVISIBLE (-5790 2435);
FORCEPROP 1 LASTPIN (-5800 2425) BN 3
J 0
(-5812 2433);
DISPLAY 0.489362 (-5812 2433);
PAINT GREEN (-5812 2433);
FORCEPROP 2 LAST CDS_LIB mstr_standard
J 0
(-5750 2425);
DISPLAY 0.723404 (-5750 2425);
PAINT MONO (-5750 2425);
DISPLAY INVISIBLE (-5750 2425);
FORCEPROP 1 LAST BODY_TYPE PLUMBING
J 0
(-5750 2475);
DISPLAY 0.872340 (-5750 2475);
PAINT GREEN (-5750 2475);
DISPLAY INVISIBLE (-5750 2475);
FORCEPROP 1 LAST HDL_TAP TRUE
J 0
(-5425 2300);
DISPLAY 0.872340 (-5425 2300);
DISPLAY INVISIBLE (-5425 2300);
FORCEPROP 1 LAST PATH I49
J 0
(-5752 2425);
DISPLAY 0.872340 (-5752 2425);
PAINT GREEN (-5752 2425);
DISPLAY INVISIBLE (-5752 2425);
FORCEADD TAP..1
(-5750 2375);
FORCEPROP 3 LASTPIN (-5800 2375) SIG_NAME M_A_CPU1_SB_DQ<2>
J 0
(-5790 2385);
DISPLAY 0.659574 (-5790 2385);
PAINT MONO (-5790 2385);
DISPLAY INVISIBLE (-5790 2385);
FORCEPROP 1 LASTPIN (-5800 2375) BN 2
J 0
(-5812 2383);
DISPLAY 0.489362 (-5812 2383);
PAINT GREEN (-5812 2383);
FORCEPROP 2 LAST CDS_LIB mstr_standard
J 0
(-5750 2375);
DISPLAY 0.723404 (-5750 2375);
PAINT MONO (-5750 2375);
DISPLAY INVISIBLE (-5750 2375);
FORCEPROP 1 LAST BODY_TYPE PLUMBING
J 0
(-5750 2425);
DISPLAY 0.872340 (-5750 2425);
PAINT GREEN (-5750 2425);
DISPLAY INVISIBLE (-5750 2425);
FORCEPROP 1 LAST HDL_TAP TRUE
J 0
(-5425 2250);
DISPLAY 0.872340 (-5425 2250);
DISPLAY INVISIBLE (-5425 2250);
FORCEPROP 1 LAST PATH I50
J 0
(-5752 2375);
DISPLAY 0.872340 (-5752 2375);
PAINT GREEN (-5752 2375);
DISPLAY INVISIBLE (-5752 2375);
FORCEADD TAP..1
(-5750 2525);
FORCEPROP 3 LASTPIN (-5800 2525) SIG_NAME M_A_CPU1_SB_DQ<5>
J 0
(-5790 2535);
DISPLAY 0.659574 (-5790 2535);
PAINT MONO (-5790 2535);
DISPLAY INVISIBLE (-5790 2535);
FORCEPROP 1 LASTPIN (-5800 2525) BN 5
J 0
(-5812 2533);
DISPLAY 0.489362 (-5812 2533);
PAINT GREEN (-5812 2533);
FORCEPROP 2 LAST CDS_LIB mstr_standard
J 0
(-5750 2525);
DISPLAY 0.723404 (-5750 2525);
PAINT MONO (-5750 2525);
DISPLAY INVISIBLE (-5750 2525);
FORCEPROP 1 LAST BODY_TYPE PLUMBING
J 0
(-5750 2575);
DISPLAY 0.872340 (-5750 2575);
PAINT GREEN (-5750 2575);
DISPLAY INVISIBLE (-5750 2575);
FORCEPROP 1 LAST HDL_TAP TRUE
J 0
(-5425 2400);
DISPLAY 0.872340 (-5425 2400);
DISPLAY INVISIBLE (-5425 2400);
FORCEPROP 1 LAST PATH I51
J 0
(-5752 2525);
DISPLAY 0.872340 (-5752 2525);
PAINT GREEN (-5752 2525);
DISPLAY INVISIBLE (-5752 2525);
FORCEADD TAP..1
(-5750 2575);
FORCEPROP 3 LASTPIN (-5800 2575) SIG_NAME M_A_CPU1_SB_DQ<6>
J 0
(-5790 2585);
DISPLAY 0.659574 (-5790 2585);
PAINT MONO (-5790 2585);
DISPLAY INVISIBLE (-5790 2585);
FORCEPROP 1 LASTPIN (-5800 2575) BN 6
J 0
(-5812 2583);
DISPLAY 0.489362 (-5812 2583);
PAINT GREEN (-5812 2583);
FORCEPROP 2 LAST CDS_LIB mstr_standard
J 0
(-5750 2575);
DISPLAY 0.723404 (-5750 2575);
PAINT MONO (-5750 2575);
DISPLAY INVISIBLE (-5750 2575);
FORCEPROP 1 LAST BODY_TYPE PLUMBING
J 0
(-5750 2625);
DISPLAY 0.872340 (-5750 2625);
PAINT GREEN (-5750 2625);
DISPLAY INVISIBLE (-5750 2625);
FORCEPROP 1 LAST HDL_TAP TRUE
J 0
(-5425 2450);
DISPLAY 0.872340 (-5425 2450);
DISPLAY INVISIBLE (-5425 2450);
FORCEPROP 1 LAST PATH I52
J 0
(-5752 2575);
DISPLAY 0.872340 (-5752 2575);
PAINT GREEN (-5752 2575);
DISPLAY INVISIBLE (-5752 2575);
FORCEADD TAP..1
(-5750 2725);
FORCEPROP 3 LASTPIN (-5800 2725) SIG_NAME M_A_CPU1_SB_DQ<9>
J 0
(-5790 2735);
DISPLAY 0.659574 (-5790 2735);
PAINT MONO (-5790 2735);
DISPLAY INVISIBLE (-5790 2735);
FORCEPROP 1 LASTPIN (-5800 2725) BN 9
J 0
(-5812 2733);
DISPLAY 0.489362 (-5812 2733);
PAINT GREEN (-5812 2733);
FORCEPROP 2 LAST CDS_LIB mstr_standard
J 0
(-5750 2725);
DISPLAY 0.723404 (-5750 2725);
PAINT MONO (-5750 2725);
DISPLAY INVISIBLE (-5750 2725);
FORCEPROP 1 LAST BODY_TYPE PLUMBING
J 0
(-5750 2775);
DISPLAY 0.872340 (-5750 2775);
PAINT GREEN (-5750 2775);
DISPLAY INVISIBLE (-5750 2775);
FORCEPROP 1 LAST HDL_TAP TRUE
J 0
(-5425 2600);
DISPLAY 0.872340 (-5425 2600);
DISPLAY INVISIBLE (-5425 2600);
FORCEPROP 1 LAST PATH I53
J 0
(-5752 2725);
DISPLAY 0.872340 (-5752 2725);
PAINT GREEN (-5752 2725);
DISPLAY INVISIBLE (-5752 2725);
FORCEADD TAP..1
(-5750 2675);
FORCEPROP 3 LASTPIN (-5800 2675) SIG_NAME M_A_CPU1_SB_DQ<8>
J 0
(-5790 2685);
DISPLAY 0.659574 (-5790 2685);
PAINT MONO (-5790 2685);
DISPLAY INVISIBLE (-5790 2685);
FORCEPROP 1 LASTPIN (-5800 2675) BN 8
J 0
(-5812 2683);
DISPLAY 0.489362 (-5812 2683);
PAINT GREEN (-5812 2683);
FORCEPROP 2 LAST CDS_LIB mstr_standard
J 0
(-5750 2675);
DISPLAY 0.723404 (-5750 2675);
PAINT MONO (-5750 2675);
DISPLAY INVISIBLE (-5750 2675);
FORCEPROP 1 LAST BODY_TYPE PLUMBING
J 0
(-5750 2725);
DISPLAY 0.872340 (-5750 2725);
PAINT GREEN (-5750 2725);
DISPLAY INVISIBLE (-5750 2725);
FORCEPROP 1 LAST HDL_TAP TRUE
J 0
(-5425 2550);
DISPLAY 0.872340 (-5425 2550);
DISPLAY INVISIBLE (-5425 2550);
FORCEPROP 1 LAST PATH I54
J 0
(-5752 2675);
DISPLAY 0.872340 (-5752 2675);
PAINT GREEN (-5752 2675);
DISPLAY INVISIBLE (-5752 2675);
FORCEADD TAP..1
(-5750 2625);
FORCEPROP 3 LASTPIN (-5800 2625) SIG_NAME M_A_CPU1_SB_DQ<7>
J 0
(-5790 2635);
DISPLAY 0.659574 (-5790 2635);
PAINT MONO (-5790 2635);
DISPLAY INVISIBLE (-5790 2635);
FORCEPROP 1 LASTPIN (-5800 2625) BN 7
J 0
(-5812 2633);
DISPLAY 0.489362 (-5812 2633);
PAINT GREEN (-5812 2633);
FORCEPROP 2 LAST CDS_LIB mstr_standard
J 0
(-5750 2625);
DISPLAY 0.723404 (-5750 2625);
PAINT MONO (-5750 2625);
DISPLAY INVISIBLE (-5750 2625);
FORCEPROP 1 LAST BODY_TYPE PLUMBING
J 0
(-5750 2675);
DISPLAY 0.872340 (-5750 2675);
PAINT GREEN (-5750 2675);
DISPLAY INVISIBLE (-5750 2675);
FORCEPROP 1 LAST HDL_TAP TRUE
J 0
(-5425 2500);
DISPLAY 0.872340 (-5425 2500);
DISPLAY INVISIBLE (-5425 2500);
FORCEPROP 1 LAST PATH I55
J 0
(-5752 2625);
DISPLAY 0.872340 (-5752 2625);
PAINT GREEN (-5752 2625);
DISPLAY INVISIBLE (-5752 2625);
FORCEADD TAP..1
(-5750 2775);
FORCEPROP 3 LASTPIN (-5800 2775) SIG_NAME M_A_CPU1_SB_DQ<10>
J 0
(-5790 2785);
DISPLAY 0.659574 (-5790 2785);
PAINT MONO (-5790 2785);
DISPLAY INVISIBLE (-5790 2785);
FORCEPROP 1 LASTPIN (-5800 2775) BN 10
J 0
(-5812 2783);
DISPLAY 0.489362 (-5812 2783);
PAINT GREEN (-5812 2783);
FORCEPROP 2 LAST CDS_LIB mstr_standard
J 0
(-5750 2775);
DISPLAY 0.723404 (-5750 2775);
PAINT MONO (-5750 2775);
DISPLAY INVISIBLE (-5750 2775);
FORCEPROP 1 LAST BODY_TYPE PLUMBING
J 0
(-5750 2825);
DISPLAY 0.872340 (-5750 2825);
PAINT GREEN (-5750 2825);
DISPLAY INVISIBLE (-5750 2825);
FORCEPROP 1 LAST HDL_TAP TRUE
J 0
(-5425 2650);
DISPLAY 0.872340 (-5425 2650);
DISPLAY INVISIBLE (-5425 2650);
FORCEPROP 1 LAST PATH I56
J 0
(-5752 2775);
DISPLAY 0.872340 (-5752 2775);
PAINT GREEN (-5752 2775);
DISPLAY INVISIBLE (-5752 2775);
FORCEADD TAP..1
(-5750 2825);
FORCEPROP 3 LASTPIN (-5800 2825) SIG_NAME M_A_CPU1_SB_DQ<11>
J 0
(-5790 2835);
DISPLAY 0.659574 (-5790 2835);
PAINT MONO (-5790 2835);
DISPLAY INVISIBLE (-5790 2835);
FORCEPROP 1 LASTPIN (-5800 2825) BN 11
J 0
(-5812 2833);
DISPLAY 0.489362 (-5812 2833);
PAINT GREEN (-5812 2833);
FORCEPROP 2 LAST CDS_LIB mstr_standard
J 0
(-5750 2825);
DISPLAY 0.723404 (-5750 2825);
PAINT MONO (-5750 2825);
DISPLAY INVISIBLE (-5750 2825);
FORCEPROP 1 LAST BODY_TYPE PLUMBING
J 0
(-5750 2875);
DISPLAY 0.872340 (-5750 2875);
PAINT GREEN (-5750 2875);
DISPLAY INVISIBLE (-5750 2875);
FORCEPROP 1 LAST HDL_TAP TRUE
J 0
(-5425 2700);
DISPLAY 0.872340 (-5425 2700);
DISPLAY INVISIBLE (-5425 2700);
FORCEPROP 1 LAST PATH I57
J 0
(-5752 2825);
DISPLAY 0.872340 (-5752 2825);
PAINT GREEN (-5752 2825);
DISPLAY INVISIBLE (-5752 2825);
FORCEADD TAP..1
(-5750 2975);
FORCEPROP 3 LASTPIN (-5800 2975) SIG_NAME M_A_CPU1_SB_DQ<14>
J 0
(-5790 2985);
DISPLAY 0.659574 (-5790 2985);
PAINT MONO (-5790 2985);
DISPLAY INVISIBLE (-5790 2985);
FORCEPROP 1 LASTPIN (-5800 2975) BN 14
J 0
(-5812 2983);
DISPLAY 0.489362 (-5812 2983);
PAINT GREEN (-5812 2983);
FORCEPROP 2 LAST CDS_LIB mstr_standard
J 0
(-5750 2975);
DISPLAY 0.723404 (-5750 2975);
PAINT MONO (-5750 2975);
DISPLAY INVISIBLE (-5750 2975);
FORCEPROP 1 LAST BODY_TYPE PLUMBING
J 0
(-5750 3025);
DISPLAY 0.872340 (-5750 3025);
PAINT GREEN (-5750 3025);
DISPLAY INVISIBLE (-5750 3025);
FORCEPROP 1 LAST HDL_TAP TRUE
J 0
(-5425 2850);
DISPLAY 0.872340 (-5425 2850);
DISPLAY INVISIBLE (-5425 2850);
FORCEPROP 1 LAST PATH I58
J 0
(-5752 2975);
DISPLAY 0.872340 (-5752 2975);
PAINT GREEN (-5752 2975);
DISPLAY INVISIBLE (-5752 2975);
FORCEADD TAP..1
(-5750 2925);
FORCEPROP 3 LASTPIN (-5800 2925) SIG_NAME M_A_CPU1_SB_DQ<13>
J 0
(-5790 2935);
DISPLAY 0.659574 (-5790 2935);
PAINT MONO (-5790 2935);
DISPLAY INVISIBLE (-5790 2935);
FORCEPROP 1 LASTPIN (-5800 2925) BN 13
J 0
(-5812 2933);
DISPLAY 0.489362 (-5812 2933);
PAINT GREEN (-5812 2933);
FORCEPROP 2 LAST CDS_LIB mstr_standard
J 0
(-5750 2925);
DISPLAY 0.723404 (-5750 2925);
PAINT MONO (-5750 2925);
DISPLAY INVISIBLE (-5750 2925);
FORCEPROP 1 LAST BODY_TYPE PLUMBING
J 0
(-5750 2975);
DISPLAY 0.872340 (-5750 2975);
PAINT GREEN (-5750 2975);
DISPLAY INVISIBLE (-5750 2975);
FORCEPROP 1 LAST HDL_TAP TRUE
J 0
(-5425 2800);
DISPLAY 0.872340 (-5425 2800);
DISPLAY INVISIBLE (-5425 2800);
FORCEPROP 1 LAST PATH I59
J 0
(-5752 2925);
DISPLAY 0.872340 (-5752 2925);
PAINT GREEN (-5752 2925);
DISPLAY INVISIBLE (-5752 2925);
FORCEADD OFFPAGE..1
(-8175 2975);
FORCEPROP 2 LAST $XR0 98 
J 0
(-8396 2975);
DISPLAY 0.638298 (-8396 2975);
PAINT MONO (-8396 2975);
FORCEPROP 2 LAST CDS_LIB mstr_standard
J 0
(-8175 2975);
DISPLAY 0.808511 (-8175 2975);
DISPLAY INVISIBLE (-8175 2975);
FORCEPROP 1 LAST OFFPAGE TRUE
J 0
(-7850 2850);
DISPLAY 0.872340 (-7850 2850);
PAINT GREEN (-7850 2850);
DISPLAY INVISIBLE (-7850 2850);
FORCEPROP 1 LAST COMMENT_BODY TRUE
J 0
(-8050 2875);
DISPLAY 0.872340 (-8050 2875);
PAINT GREEN (-8050 2875);
DISPLAY INVISIBLE (-8050 2875);
FORCEPROP 2 LAST PATH I6
J 0
(-8425 3025);
DISPLAY 1.021277 (-8425 3025);
DISPLAY INVISIBLE (-8425 3025);
FORCEADD TAP..1
(-5750 2875);
FORCEPROP 3 LASTPIN (-5800 2875) SIG_NAME M_A_CPU1_SB_DQ<12>
J 0
(-5790 2885);
DISPLAY 0.659574 (-5790 2885);
PAINT MONO (-5790 2885);
DISPLAY INVISIBLE (-5790 2885);
FORCEPROP 1 LASTPIN (-5800 2875) BN 12
J 0
(-5812 2883);
DISPLAY 0.489362 (-5812 2883);
PAINT GREEN (-5812 2883);
FORCEPROP 2 LAST CDS_LIB mstr_standard
J 0
(-5750 2875);
DISPLAY 0.723404 (-5750 2875);
PAINT MONO (-5750 2875);
DISPLAY INVISIBLE (-5750 2875);
FORCEPROP 1 LAST BODY_TYPE PLUMBING
J 0
(-5750 2925);
DISPLAY 0.872340 (-5750 2925);
PAINT GREEN (-5750 2925);
DISPLAY INVISIBLE (-5750 2925);
FORCEPROP 1 LAST HDL_TAP TRUE
J 0
(-5425 2750);
DISPLAY 0.872340 (-5425 2750);
DISPLAY INVISIBLE (-5425 2750);
FORCEPROP 1 LAST PATH I60
J 0
(-5752 2875);
DISPLAY 0.872340 (-5752 2875);
PAINT GREEN (-5752 2875);
DISPLAY INVISIBLE (-5752 2875);
FORCEADD TAP..1
(-5750 3075);
FORCEPROP 3 LASTPIN (-5800 3075) SIG_NAME M_A_CPU1_SB_DQ<16>
J 0
(-5790 3085);
DISPLAY 0.659574 (-5790 3085);
PAINT MONO (-5790 3085);
DISPLAY INVISIBLE (-5790 3085);
FORCEPROP 1 LASTPIN (-5800 3075) BN 16
J 0
(-5812 3083);
DISPLAY 0.489362 (-5812 3083);
PAINT GREEN (-5812 3083);
FORCEPROP 2 LAST CDS_LIB mstr_standard
J 0
(-5750 3075);
DISPLAY 0.723404 (-5750 3075);
PAINT MONO (-5750 3075);
DISPLAY INVISIBLE (-5750 3075);
FORCEPROP 1 LAST BODY_TYPE PLUMBING
J 0
(-5750 3125);
DISPLAY 0.872340 (-5750 3125);
PAINT GREEN (-5750 3125);
DISPLAY INVISIBLE (-5750 3125);
FORCEPROP 1 LAST HDL_TAP TRUE
J 0
(-5425 2950);
DISPLAY 0.872340 (-5425 2950);
DISPLAY INVISIBLE (-5425 2950);
FORCEPROP 1 LAST PATH I61
J 0
(-5752 3075);
DISPLAY 0.872340 (-5752 3075);
PAINT GREEN (-5752 3075);
DISPLAY INVISIBLE (-5752 3075);
FORCEADD TAP..1
(-5750 3025);
FORCEPROP 3 LASTPIN (-5800 3025) SIG_NAME M_A_CPU1_SB_DQ<15>
J 0
(-5790 3035);
DISPLAY 0.659574 (-5790 3035);
PAINT MONO (-5790 3035);
DISPLAY INVISIBLE (-5790 3035);
FORCEPROP 1 LASTPIN (-5800 3025) BN 15
J 0
(-5812 3033);
DISPLAY 0.489362 (-5812 3033);
PAINT GREEN (-5812 3033);
FORCEPROP 2 LAST CDS_LIB mstr_standard
J 0
(-5750 3025);
DISPLAY 0.723404 (-5750 3025);
PAINT MONO (-5750 3025);
DISPLAY INVISIBLE (-5750 3025);
FORCEPROP 1 LAST BODY_TYPE PLUMBING
J 0
(-5750 3075);
DISPLAY 0.872340 (-5750 3075);
PAINT GREEN (-5750 3075);
DISPLAY INVISIBLE (-5750 3075);
FORCEPROP 1 LAST HDL_TAP TRUE
J 0
(-5425 2900);
DISPLAY 0.872340 (-5425 2900);
DISPLAY INVISIBLE (-5425 2900);
FORCEPROP 1 LAST PATH I62
J 0
(-5752 3025);
DISPLAY 0.872340 (-5752 3025);
PAINT GREEN (-5752 3025);
DISPLAY INVISIBLE (-5752 3025);
FORCEADD TAP..1
(-5750 3125);
FORCEPROP 3 LASTPIN (-5800 3125) SIG_NAME M_A_CPU1_SB_DQ<17>
J 0
(-5790 3135);
DISPLAY 0.659574 (-5790 3135);
PAINT MONO (-5790 3135);
DISPLAY INVISIBLE (-5790 3135);
FORCEPROP 1 LASTPIN (-5800 3125) BN 17
J 0
(-5812 3133);
DISPLAY 0.489362 (-5812 3133);
PAINT GREEN (-5812 3133);
FORCEPROP 2 LAST CDS_LIB mstr_standard
J 0
(-5750 3125);
DISPLAY 0.723404 (-5750 3125);
PAINT MONO (-5750 3125);
DISPLAY INVISIBLE (-5750 3125);
FORCEPROP 1 LAST BODY_TYPE PLUMBING
J 0
(-5750 3175);
DISPLAY 0.872340 (-5750 3175);
PAINT GREEN (-5750 3175);
DISPLAY INVISIBLE (-5750 3175);
FORCEPROP 1 LAST HDL_TAP TRUE
J 0
(-5425 3000);
DISPLAY 0.872340 (-5425 3000);
DISPLAY INVISIBLE (-5425 3000);
FORCEPROP 1 LAST PATH I63
J 0
(-5752 3125);
DISPLAY 0.872340 (-5752 3125);
PAINT GREEN (-5752 3125);
DISPLAY INVISIBLE (-5752 3125);
FORCEADD TAP..1
(-5750 3225);
FORCEPROP 3 LASTPIN (-5800 3225) SIG_NAME M_A_CPU1_SB_DQ<19>
J 0
(-5790 3235);
DISPLAY 0.659574 (-5790 3235);
PAINT MONO (-5790 3235);
DISPLAY INVISIBLE (-5790 3235);
FORCEPROP 1 LASTPIN (-5800 3225) BN 19
J 0
(-5812 3233);
DISPLAY 0.489362 (-5812 3233);
PAINT GREEN (-5812 3233);
FORCEPROP 2 LAST CDS_LIB mstr_standard
J 0
(-5750 3225);
DISPLAY 0.723404 (-5750 3225);
PAINT MONO (-5750 3225);
DISPLAY INVISIBLE (-5750 3225);
FORCEPROP 1 LAST BODY_TYPE PLUMBING
J 0
(-5750 3275);
DISPLAY 0.872340 (-5750 3275);
PAINT GREEN (-5750 3275);
DISPLAY INVISIBLE (-5750 3275);
FORCEPROP 1 LAST HDL_TAP TRUE
J 0
(-5425 3100);
DISPLAY 0.872340 (-5425 3100);
DISPLAY INVISIBLE (-5425 3100);
FORCEPROP 1 LAST PATH I64
J 0
(-5752 3225);
DISPLAY 0.872340 (-5752 3225);
PAINT GREEN (-5752 3225);
DISPLAY INVISIBLE (-5752 3225);
FORCEADD TAP..1
(-5750 3175);
FORCEPROP 3 LASTPIN (-5800 3175) SIG_NAME M_A_CPU1_SB_DQ<18>
J 0
(-5790 3185);
DISPLAY 0.659574 (-5790 3185);
PAINT MONO (-5790 3185);
DISPLAY INVISIBLE (-5790 3185);
FORCEPROP 1 LASTPIN (-5800 3175) BN 18
J 0
(-5812 3183);
DISPLAY 0.489362 (-5812 3183);
PAINT GREEN (-5812 3183);
FORCEPROP 2 LAST CDS_LIB mstr_standard
J 0
(-5750 3175);
DISPLAY 0.723404 (-5750 3175);
PAINT MONO (-5750 3175);
DISPLAY INVISIBLE (-5750 3175);
FORCEPROP 1 LAST BODY_TYPE PLUMBING
J 0
(-5750 3225);
DISPLAY 0.872340 (-5750 3225);
PAINT GREEN (-5750 3225);
DISPLAY INVISIBLE (-5750 3225);
FORCEPROP 1 LAST HDL_TAP TRUE
J 0
(-5425 3050);
DISPLAY 0.872340 (-5425 3050);
DISPLAY INVISIBLE (-5425 3050);
FORCEPROP 1 LAST PATH I65
J 0
(-5752 3175);
DISPLAY 0.872340 (-5752 3175);
PAINT GREEN (-5752 3175);
DISPLAY INVISIBLE (-5752 3175);
FORCEADD TAP..1
(-5750 3275);
FORCEPROP 3 LASTPIN (-5800 3275) SIG_NAME M_A_CPU1_SB_DQ<20>
J 0
(-5790 3285);
DISPLAY 0.659574 (-5790 3285);
PAINT MONO (-5790 3285);
DISPLAY INVISIBLE (-5790 3285);
FORCEPROP 1 LASTPIN (-5800 3275) BN 20
J 0
(-5812 3283);
DISPLAY 0.489362 (-5812 3283);
PAINT GREEN (-5812 3283);
FORCEPROP 2 LAST CDS_LIB mstr_standard
J 0
(-5750 3275);
DISPLAY 0.723404 (-5750 3275);
PAINT MONO (-5750 3275);
DISPLAY INVISIBLE (-5750 3275);
FORCEPROP 1 LAST BODY_TYPE PLUMBING
J 0
(-5750 3325);
DISPLAY 0.872340 (-5750 3325);
PAINT GREEN (-5750 3325);
DISPLAY INVISIBLE (-5750 3325);
FORCEPROP 1 LAST HDL_TAP TRUE
J 0
(-5425 3150);
DISPLAY 0.872340 (-5425 3150);
DISPLAY INVISIBLE (-5425 3150);
FORCEPROP 1 LAST PATH I66
J 0
(-5752 3275);
DISPLAY 0.872340 (-5752 3275);
PAINT GREEN (-5752 3275);
DISPLAY INVISIBLE (-5752 3275);
FORCEADD TAP..1
(-5750 3325);
FORCEPROP 3 LASTPIN (-5800 3325) SIG_NAME M_A_CPU1_SB_DQ<21>
J 0
(-5790 3335);
DISPLAY 0.659574 (-5790 3335);
PAINT MONO (-5790 3335);
DISPLAY INVISIBLE (-5790 3335);
FORCEPROP 1 LASTPIN (-5800 3325) BN 21
J 0
(-5812 3333);
DISPLAY 0.489362 (-5812 3333);
PAINT GREEN (-5812 3333);
FORCEPROP 2 LAST CDS_LIB mstr_standard
J 0
(-5750 3325);
DISPLAY 0.723404 (-5750 3325);
PAINT MONO (-5750 3325);
DISPLAY INVISIBLE (-5750 3325);
FORCEPROP 1 LAST BODY_TYPE PLUMBING
J 0
(-5750 3375);
DISPLAY 0.872340 (-5750 3375);
PAINT GREEN (-5750 3375);
DISPLAY INVISIBLE (-5750 3375);
FORCEPROP 1 LAST HDL_TAP TRUE
J 0
(-5425 3200);
DISPLAY 0.872340 (-5425 3200);
DISPLAY INVISIBLE (-5425 3200);
FORCEPROP 1 LAST PATH I67
J 0
(-5752 3325);
DISPLAY 0.872340 (-5752 3325);
PAINT GREEN (-5752 3325);
DISPLAY INVISIBLE (-5752 3325);
FORCEADD TAP..1
(-5750 3375);
FORCEPROP 3 LASTPIN (-5800 3375) SIG_NAME M_A_CPU1_SB_DQ<22>
J 0
(-5790 3385);
DISPLAY 0.659574 (-5790 3385);
PAINT MONO (-5790 3385);
DISPLAY INVISIBLE (-5790 3385);
FORCEPROP 1 LASTPIN (-5800 3375) BN 22
J 0
(-5812 3383);
DISPLAY 0.489362 (-5812 3383);
PAINT GREEN (-5812 3383);
FORCEPROP 2 LAST CDS_LIB mstr_standard
J 0
(-5750 3375);
DISPLAY 0.723404 (-5750 3375);
PAINT MONO (-5750 3375);
DISPLAY INVISIBLE (-5750 3375);
FORCEPROP 1 LAST BODY_TYPE PLUMBING
J 0
(-5750 3425);
DISPLAY 0.872340 (-5750 3425);
PAINT GREEN (-5750 3425);
DISPLAY INVISIBLE (-5750 3425);
FORCEPROP 1 LAST HDL_TAP TRUE
J 0
(-5425 3250);
DISPLAY 0.872340 (-5425 3250);
DISPLAY INVISIBLE (-5425 3250);
FORCEPROP 1 LAST PATH I68
J 0
(-5752 3375);
DISPLAY 0.872340 (-5752 3375);
PAINT GREEN (-5752 3375);
DISPLAY INVISIBLE (-5752 3375);
FORCEADD TAP..1
(-5750 3475);
FORCEPROP 3 LASTPIN (-5800 3475) SIG_NAME M_A_CPU1_SB_DQ<24>
J 0
(-5790 3485);
DISPLAY 0.659574 (-5790 3485);
PAINT MONO (-5790 3485);
DISPLAY INVISIBLE (-5790 3485);
FORCEPROP 1 LASTPIN (-5800 3475) BN 24
J 0
(-5812 3483);
DISPLAY 0.489362 (-5812 3483);
PAINT GREEN (-5812 3483);
FORCEPROP 2 LAST CDS_LIB mstr_standard
J 0
(-5750 3475);
DISPLAY 0.723404 (-5750 3475);
PAINT MONO (-5750 3475);
DISPLAY INVISIBLE (-5750 3475);
FORCEPROP 1 LAST BODY_TYPE PLUMBING
J 0
(-5750 3525);
DISPLAY 0.872340 (-5750 3525);
PAINT GREEN (-5750 3525);
DISPLAY INVISIBLE (-5750 3525);
FORCEPROP 1 LAST HDL_TAP TRUE
J 0
(-5425 3350);
DISPLAY 0.872340 (-5425 3350);
DISPLAY INVISIBLE (-5425 3350);
FORCEPROP 1 LAST PATH I69
J 0
(-5752 3475);
DISPLAY 0.872340 (-5752 3475);
PAINT GREEN (-5752 3475);
DISPLAY INVISIBLE (-5752 3475);
FORCEADD OFFPAGE..5
(-8050 3125);
FORCEPROP 2 LAST $XR0 37 
J 0
(-8304 3125);
DISPLAY 0.638298 (-8304 3125);
PAINT MONO (-8304 3125);
FORCEPROP 2 LAST CDS_LIB mstr_standard
J 0
(-8050 3125);
DISPLAY INVISIBLE (-8050 3125);
FORCEPROP 1 LAST OFFPAGE TRUE
J 0
(-7725 3000);
DISPLAY 0.872340 (-7725 3000);
PAINT GREEN (-7725 3000);
DISPLAY INVISIBLE (-7725 3000);
FORCEPROP 1 LAST COMMENT_BODY TRUE
J 0
(-7950 3050);
DISPLAY 0.872340 (-7950 3050);
PAINT GREEN (-7950 3050);
DISPLAY INVISIBLE (-7950 3050);
FORCEPROP 2 LAST PATH I7
J 0
(-8300 3175);
DISPLAY 1.021277 (-8300 3175);
DISPLAY INVISIBLE (-8300 3175);
FORCEADD TAP..1
(-5750 3425);
FORCEPROP 3 LASTPIN (-5800 3425) SIG_NAME M_A_CPU1_SB_DQ<23>
J 0
(-5790 3435);
DISPLAY 0.659574 (-5790 3435);
PAINT MONO (-5790 3435);
DISPLAY INVISIBLE (-5790 3435);
FORCEPROP 1 LASTPIN (-5800 3425) BN 23
J 0
(-5812 3433);
DISPLAY 0.489362 (-5812 3433);
PAINT GREEN (-5812 3433);
FORCEPROP 2 LAST CDS_LIB mstr_standard
J 0
(-5750 3425);
DISPLAY 0.723404 (-5750 3425);
PAINT MONO (-5750 3425);
DISPLAY INVISIBLE (-5750 3425);
FORCEPROP 1 LAST BODY_TYPE PLUMBING
J 0
(-5750 3475);
DISPLAY 0.872340 (-5750 3475);
PAINT GREEN (-5750 3475);
DISPLAY INVISIBLE (-5750 3475);
FORCEPROP 1 LAST HDL_TAP TRUE
J 0
(-5425 3300);
DISPLAY 0.872340 (-5425 3300);
DISPLAY INVISIBLE (-5425 3300);
FORCEPROP 1 LAST PATH I70
J 0
(-5752 3425);
DISPLAY 0.872340 (-5752 3425);
PAINT GREEN (-5752 3425);
DISPLAY INVISIBLE (-5752 3425);
FORCEADD TAP..1
(-5750 3525);
FORCEPROP 3 LASTPIN (-5800 3525) SIG_NAME M_A_CPU1_SB_DQ<25>
J 0
(-5790 3535);
DISPLAY 0.659574 (-5790 3535);
PAINT MONO (-5790 3535);
DISPLAY INVISIBLE (-5790 3535);
FORCEPROP 1 LASTPIN (-5800 3525) BN 25
J 0
(-5812 3533);
DISPLAY 0.489362 (-5812 3533);
PAINT GREEN (-5812 3533);
FORCEPROP 2 LAST CDS_LIB mstr_standard
J 0
(-5750 3525);
DISPLAY 0.723404 (-5750 3525);
PAINT MONO (-5750 3525);
DISPLAY INVISIBLE (-5750 3525);
FORCEPROP 1 LAST BODY_TYPE PLUMBING
J 0
(-5750 3575);
DISPLAY 0.872340 (-5750 3575);
PAINT GREEN (-5750 3575);
DISPLAY INVISIBLE (-5750 3575);
FORCEPROP 1 LAST HDL_TAP TRUE
J 0
(-5425 3400);
DISPLAY 0.872340 (-5425 3400);
DISPLAY INVISIBLE (-5425 3400);
FORCEPROP 1 LAST PATH I71
J 0
(-5752 3525);
DISPLAY 0.872340 (-5752 3525);
PAINT GREEN (-5752 3525);
DISPLAY INVISIBLE (-5752 3525);
FORCEADD TAP..1
(-5750 3575);
FORCEPROP 3 LASTPIN (-5800 3575) SIG_NAME M_A_CPU1_SB_DQ<26>
J 0
(-5790 3585);
DISPLAY 0.659574 (-5790 3585);
PAINT MONO (-5790 3585);
DISPLAY INVISIBLE (-5790 3585);
FORCEPROP 1 LASTPIN (-5800 3575) BN 26
J 0
(-5812 3583);
DISPLAY 0.489362 (-5812 3583);
PAINT GREEN (-5812 3583);
FORCEPROP 2 LAST CDS_LIB mstr_standard
J 0
(-5750 3575);
DISPLAY 0.723404 (-5750 3575);
PAINT MONO (-5750 3575);
DISPLAY INVISIBLE (-5750 3575);
FORCEPROP 1 LAST BODY_TYPE PLUMBING
J 0
(-5750 3625);
DISPLAY 0.872340 (-5750 3625);
PAINT GREEN (-5750 3625);
DISPLAY INVISIBLE (-5750 3625);
FORCEPROP 1 LAST HDL_TAP TRUE
J 0
(-5425 3450);
DISPLAY 0.872340 (-5425 3450);
DISPLAY INVISIBLE (-5425 3450);
FORCEPROP 1 LAST PATH I72
J 0
(-5752 3575);
DISPLAY 0.872340 (-5752 3575);
PAINT GREEN (-5752 3575);
DISPLAY INVISIBLE (-5752 3575);
FORCEADD TAP..1
(-5750 3625);
FORCEPROP 3 LASTPIN (-5800 3625) SIG_NAME M_A_CPU1_SB_DQ<27>
J 0
(-5790 3635);
DISPLAY 0.659574 (-5790 3635);
PAINT MONO (-5790 3635);
DISPLAY INVISIBLE (-5790 3635);
FORCEPROP 1 LASTPIN (-5800 3625) BN 27
J 0
(-5812 3633);
DISPLAY 0.489362 (-5812 3633);
PAINT GREEN (-5812 3633);
FORCEPROP 2 LAST CDS_LIB mstr_standard
J 0
(-5750 3625);
DISPLAY 0.723404 (-5750 3625);
PAINT MONO (-5750 3625);
DISPLAY INVISIBLE (-5750 3625);
FORCEPROP 1 LAST BODY_TYPE PLUMBING
J 0
(-5750 3675);
DISPLAY 0.872340 (-5750 3675);
PAINT GREEN (-5750 3675);
DISPLAY INVISIBLE (-5750 3675);
FORCEPROP 1 LAST HDL_TAP TRUE
J 0
(-5425 3500);
DISPLAY 0.872340 (-5425 3500);
DISPLAY INVISIBLE (-5425 3500);
FORCEPROP 1 LAST PATH I73
J 0
(-5752 3625);
DISPLAY 0.872340 (-5752 3625);
PAINT GREEN (-5752 3625);
DISPLAY INVISIBLE (-5752 3625);
FORCEADD TAP..1
(-5750 3725);
FORCEPROP 3 LASTPIN (-5800 3725) SIG_NAME M_A_CPU1_SB_DQ<29>
J 0
(-5790 3735);
DISPLAY 0.659574 (-5790 3735);
PAINT MONO (-5790 3735);
DISPLAY INVISIBLE (-5790 3735);
FORCEPROP 1 LASTPIN (-5800 3725) BN 29
J 0
(-5812 3733);
DISPLAY 0.489362 (-5812 3733);
PAINT GREEN (-5812 3733);
FORCEPROP 2 LAST CDS_LIB mstr_standard
J 0
(-5750 3725);
DISPLAY 0.723404 (-5750 3725);
PAINT MONO (-5750 3725);
DISPLAY INVISIBLE (-5750 3725);
FORCEPROP 1 LAST BODY_TYPE PLUMBING
J 0
(-5750 3775);
DISPLAY 0.872340 (-5750 3775);
PAINT GREEN (-5750 3775);
DISPLAY INVISIBLE (-5750 3775);
FORCEPROP 1 LAST HDL_TAP TRUE
J 0
(-5425 3600);
DISPLAY 0.872340 (-5425 3600);
DISPLAY INVISIBLE (-5425 3600);
FORCEPROP 1 LAST PATH I74
J 0
(-5752 3725);
DISPLAY 0.872340 (-5752 3725);
PAINT GREEN (-5752 3725);
DISPLAY INVISIBLE (-5752 3725);
FORCEADD TAP..1
(-5750 3675);
FORCEPROP 3 LASTPIN (-5800 3675) SIG_NAME M_A_CPU1_SB_DQ<28>
J 0
(-5790 3685);
DISPLAY 0.659574 (-5790 3685);
PAINT MONO (-5790 3685);
DISPLAY INVISIBLE (-5790 3685);
FORCEPROP 1 LASTPIN (-5800 3675) BN 28
J 0
(-5812 3683);
DISPLAY 0.489362 (-5812 3683);
PAINT GREEN (-5812 3683);
FORCEPROP 2 LAST CDS_LIB mstr_standard
J 0
(-5750 3675);
DISPLAY 0.723404 (-5750 3675);
PAINT MONO (-5750 3675);
DISPLAY INVISIBLE (-5750 3675);
FORCEPROP 1 LAST BODY_TYPE PLUMBING
J 0
(-5750 3725);
DISPLAY 0.872340 (-5750 3725);
PAINT GREEN (-5750 3725);
DISPLAY INVISIBLE (-5750 3725);
FORCEPROP 1 LAST HDL_TAP TRUE
J 0
(-5425 3550);
DISPLAY 0.872340 (-5425 3550);
DISPLAY INVISIBLE (-5425 3550);
FORCEPROP 1 LAST PATH I75
J 0
(-5752 3675);
DISPLAY 0.872340 (-5752 3675);
PAINT GREEN (-5752 3675);
DISPLAY INVISIBLE (-5752 3675);
FORCEADD TAP..1
(-5750 3775);
FORCEPROP 3 LASTPIN (-5800 3775) SIG_NAME M_A_CPU1_SB_DQ<30>
J 0
(-5790 3785);
DISPLAY 0.659574 (-5790 3785);
PAINT MONO (-5790 3785);
DISPLAY INVISIBLE (-5790 3785);
FORCEPROP 1 LASTPIN (-5800 3775) BN 30
J 0
(-5812 3783);
DISPLAY 0.489362 (-5812 3783);
PAINT GREEN (-5812 3783);
FORCEPROP 2 LAST CDS_LIB mstr_standard
J 0
(-5750 3775);
DISPLAY 0.723404 (-5750 3775);
PAINT MONO (-5750 3775);
DISPLAY INVISIBLE (-5750 3775);
FORCEPROP 1 LAST BODY_TYPE PLUMBING
J 0
(-5750 3825);
DISPLAY 0.872340 (-5750 3825);
PAINT GREEN (-5750 3825);
DISPLAY INVISIBLE (-5750 3825);
FORCEPROP 1 LAST HDL_TAP TRUE
J 0
(-5425 3650);
DISPLAY 0.872340 (-5425 3650);
DISPLAY INVISIBLE (-5425 3650);
FORCEPROP 1 LAST PATH I76
J 0
(-5752 3775);
DISPLAY 0.872340 (-5752 3775);
PAINT GREEN (-5752 3775);
DISPLAY INVISIBLE (-5752 3775);
FORCEADD TAP..1
(-5750 3825);
FORCEPROP 3 LASTPIN (-5800 3825) SIG_NAME M_A_CPU1_SB_DQ<31>
J 0
(-5790 3835);
DISPLAY 0.659574 (-5790 3835);
PAINT MONO (-5790 3835);
DISPLAY INVISIBLE (-5790 3835);
FORCEPROP 1 LASTPIN (-5800 3825) BN 31
J 0
(-5812 3833);
DISPLAY 0.489362 (-5812 3833);
PAINT GREEN (-5812 3833);
FORCEPROP 2 LAST CDS_LIB mstr_standard
J 0
(-5750 3825);
DISPLAY 0.723404 (-5750 3825);
PAINT MONO (-5750 3825);
DISPLAY INVISIBLE (-5750 3825);
FORCEPROP 1 LAST BODY_TYPE PLUMBING
J 0
(-5750 3875);
DISPLAY 0.872340 (-5750 3875);
PAINT GREEN (-5750 3875);
DISPLAY INVISIBLE (-5750 3875);
FORCEPROP 1 LAST HDL_TAP TRUE
J 0
(-5425 3700);
DISPLAY 0.872340 (-5425 3700);
DISPLAY INVISIBLE (-5425 3700);
FORCEPROP 1 LAST PATH I77
J 0
(-5752 3825);
DISPLAY 0.872340 (-5752 3825);
PAINT GREEN (-5752 3825);
DISPLAY INVISIBLE (-5752 3825);
FORCEADD TAP..1
(-5750 3975);
FORCEPROP 3 LASTPIN (-5800 3975) SIG_NAME M_A_CPU1_SA_DQ<1>
J 0
(-5790 3985);
DISPLAY 0.659574 (-5790 3985);
PAINT MONO (-5790 3985);
DISPLAY INVISIBLE (-5790 3985);
FORCEPROP 1 LASTPIN (-5800 3975) BN 1
J 0
(-5812 3983);
DISPLAY 0.489362 (-5812 3983);
PAINT GREEN (-5812 3983);
FORCEPROP 2 LAST CDS_LIB mstr_standard
J 0
(-5750 3975);
DISPLAY 0.723404 (-5750 3975);
PAINT MONO (-5750 3975);
DISPLAY INVISIBLE (-5750 3975);
FORCEPROP 1 LAST BODY_TYPE PLUMBING
J 0
(-5750 4025);
DISPLAY 0.872340 (-5750 4025);
PAINT GREEN (-5750 4025);
DISPLAY INVISIBLE (-5750 4025);
FORCEPROP 1 LAST HDL_TAP TRUE
J 0
(-5425 3850);
DISPLAY 0.872340 (-5425 3850);
DISPLAY INVISIBLE (-5425 3850);
FORCEPROP 1 LAST PATH I78
J 0
(-5752 3975);
DISPLAY 0.872340 (-5752 3975);
PAINT GREEN (-5752 3975);
DISPLAY INVISIBLE (-5752 3975);
FORCEADD TAP..1
(-5750 3925);
FORCEPROP 3 LASTPIN (-5800 3925) SIG_NAME M_A_CPU1_SA_DQ<0>
J 0
(-5790 3935);
DISPLAY 0.659574 (-5790 3935);
PAINT MONO (-5790 3935);
DISPLAY INVISIBLE (-5790 3935);
FORCEPROP 1 LASTPIN (-5800 3925) BN 0
J 0
(-5812 3933);
DISPLAY 0.489362 (-5812 3933);
PAINT GREEN (-5812 3933);
FORCEPROP 2 LAST CDS_LIB mstr_standard
J 0
(-5750 3925);
DISPLAY 0.723404 (-5750 3925);
PAINT MONO (-5750 3925);
DISPLAY INVISIBLE (-5750 3925);
FORCEPROP 1 LAST BODY_TYPE PLUMBING
J 0
(-5750 3975);
DISPLAY 0.872340 (-5750 3975);
PAINT GREEN (-5750 3975);
DISPLAY INVISIBLE (-5750 3975);
FORCEPROP 1 LAST HDL_TAP TRUE
J 0
(-5425 3800);
DISPLAY 0.872340 (-5425 3800);
DISPLAY INVISIBLE (-5425 3800);
FORCEPROP 1 LAST PATH I79
J 0
(-5752 3925);
DISPLAY 0.872340 (-5752 3925);
PAINT GREEN (-5752 3925);
DISPLAY INVISIBLE (-5752 3925);
FORCEADD VCC_CORE..1
(-8500 3550);
FORCEPROP 3 LASTPIN (-8500 3500) SIG_NAME P3V3_AUX\g
J 0
(-8490 3510);
DISPLAY 0.659574 (-8490 3510);
PAINT MONO (-8490 3510);
DISPLAY INVISIBLE (-8490 3510);
FORCEPROP 1 LAST HDL_POWER P3V3_AUX
J 1
(-8500 3600);
DISPLAY 0.489362 (-8500 3600);
PAINT GREEN (-8500 3600);
FORCEPROP 2 LAST CDS_LIB mstr_symbols
J 0
(-8500 3550);
PAINT MONO (-8500 3550);
DISPLAY INVISIBLE (-8500 3550);
FORCEPROP 0 LAST VOLTAGE 3.3
J 0
(-8775 3700);
DISPLAY 1.021277 (-8775 3700);
PAINT SKYBLUE (-8775 3700);
DISPLAY INVISIBLE (-8775 3700);
FORCEPROP 2 LAST ROOM PVCCINFAON_CPU1_CTRL
J 0
(-8500 3650);
DISPLAY 0.808511 (-8500 3650);
PAINT RED (-8500 3650);
DISPLAY INVISIBLE (-8500 3650);
FORCEPROP 1 LAST PATH I8
J 0
(-8450 3575);
DISPLAY 0.872340 (-8450 3575);
PAINT AQUA (-8450 3575);
DISPLAY INVISIBLE (-8450 3575);
FORCEADD TAP..1
(-5750 4075);
FORCEPROP 3 LASTPIN (-5800 4075) SIG_NAME M_A_CPU1_SA_DQ<3>
J 0
(-5790 4085);
DISPLAY 0.659574 (-5790 4085);
PAINT MONO (-5790 4085);
DISPLAY INVISIBLE (-5790 4085);
FORCEPROP 1 LASTPIN (-5800 4075) BN 3
J 0
(-5812 4083);
DISPLAY 0.489362 (-5812 4083);
PAINT GREEN (-5812 4083);
FORCEPROP 2 LAST CDS_LIB mstr_standard
J 0
(-5750 4075);
DISPLAY 0.723404 (-5750 4075);
PAINT MONO (-5750 4075);
DISPLAY INVISIBLE (-5750 4075);
FORCEPROP 1 LAST BODY_TYPE PLUMBING
J 0
(-5750 4125);
DISPLAY 0.872340 (-5750 4125);
PAINT GREEN (-5750 4125);
DISPLAY INVISIBLE (-5750 4125);
FORCEPROP 1 LAST HDL_TAP TRUE
J 0
(-5425 3950);
DISPLAY 0.872340 (-5425 3950);
DISPLAY INVISIBLE (-5425 3950);
FORCEPROP 1 LAST PATH I80
J 0
(-5752 4075);
DISPLAY 0.872340 (-5752 4075);
PAINT GREEN (-5752 4075);
DISPLAY INVISIBLE (-5752 4075);
FORCEADD TAP..1
(-5750 4125);
FORCEPROP 3 LASTPIN (-5800 4125) SIG_NAME M_A_CPU1_SA_DQ<4>
J 0
(-5790 4135);
DISPLAY 0.659574 (-5790 4135);
PAINT MONO (-5790 4135);
DISPLAY INVISIBLE (-5790 4135);
FORCEPROP 1 LASTPIN (-5800 4125) BN 4
J 0
(-5812 4133);
DISPLAY 0.489362 (-5812 4133);
PAINT GREEN (-5812 4133);
FORCEPROP 2 LAST CDS_LIB mstr_standard
J 0
(-5750 4125);
DISPLAY 0.723404 (-5750 4125);
PAINT MONO (-5750 4125);
DISPLAY INVISIBLE (-5750 4125);
FORCEPROP 1 LAST BODY_TYPE PLUMBING
J 0
(-5750 4175);
DISPLAY 0.872340 (-5750 4175);
PAINT GREEN (-5750 4175);
DISPLAY INVISIBLE (-5750 4175);
FORCEPROP 1 LAST HDL_TAP TRUE
J 0
(-5425 4000);
DISPLAY 0.872340 (-5425 4000);
DISPLAY INVISIBLE (-5425 4000);
FORCEPROP 1 LAST PATH I81
J 0
(-5752 4125);
DISPLAY 0.872340 (-5752 4125);
PAINT GREEN (-5752 4125);
DISPLAY INVISIBLE (-5752 4125);
FORCEADD TAP..1
(-5750 4025);
FORCEPROP 3 LASTPIN (-5800 4025) SIG_NAME M_A_CPU1_SA_DQ<2>
J 0
(-5790 4035);
DISPLAY 0.659574 (-5790 4035);
PAINT MONO (-5790 4035);
DISPLAY INVISIBLE (-5790 4035);
FORCEPROP 1 LASTPIN (-5800 4025) BN 2
J 0
(-5812 4033);
DISPLAY 0.489362 (-5812 4033);
PAINT GREEN (-5812 4033);
FORCEPROP 2 LAST CDS_LIB mstr_standard
J 0
(-5750 4025);
DISPLAY 0.723404 (-5750 4025);
PAINT MONO (-5750 4025);
DISPLAY INVISIBLE (-5750 4025);
FORCEPROP 1 LAST BODY_TYPE PLUMBING
J 0
(-5750 4075);
DISPLAY 0.872340 (-5750 4075);
PAINT GREEN (-5750 4075);
DISPLAY INVISIBLE (-5750 4075);
FORCEPROP 1 LAST HDL_TAP TRUE
J 0
(-5425 3900);
DISPLAY 0.872340 (-5425 3900);
DISPLAY INVISIBLE (-5425 3900);
FORCEPROP 1 LAST PATH I82
J 0
(-5752 4025);
DISPLAY 0.872340 (-5752 4025);
PAINT GREEN (-5752 4025);
DISPLAY INVISIBLE (-5752 4025);
FORCEADD OFFPAGE..3
(-5150 3875);
FORCEPROP 2 LAST $XR0 37 
J 0
(-4936 3875);
DISPLAY 0.638298 (-4936 3875);
PAINT MONO (-4936 3875);
FORCEPROP 2 LAST CDS_LIB mstr_standard
J 0
(-5150 3875);
DISPLAY 0.723404 (-5150 3875);
PAINT MONO (-5150 3875);
DISPLAY INVISIBLE (-5150 3875);
FORCEPROP 1 LAST OFFPAGE TRUE
J 0
(-4825 3750);
DISPLAY 0.872340 (-4825 3750);
PAINT GREEN (-4825 3750);
DISPLAY INVISIBLE (-4825 3750);
FORCEPROP 1 LAST COMMENT_BODY TRUE
J 0
(-5200 3775);
DISPLAY 0.872340 (-5200 3775);
PAINT GREEN (-5200 3775);
DISPLAY INVISIBLE (-5200 3775);
FORCEPROP 2 LAST PATH I83
J 0
(-4825 3925);
DISPLAY 1.021277 (-4825 3925);
DISPLAY INVISIBLE (-4825 3925);
FORCEADD TAP..1
R 2
(-7450 4775);
FORCEPROP 3 LASTPIN (-7400 4775) SIG_NAME M_A_CPU1_SB_CA<0>
J 0
(-7390 4785);
DISPLAY 0.659574 (-7390 4785);
PAINT MONO (-7390 4785);
DISPLAY INVISIBLE (-7390 4785);
FORCEPROP 1 LASTPIN (-7400 4775) BN 0
J 2
(-7388 4783);
DISPLAY 0.489362 (-7388 4783);
PAINT GREEN (-7388 4783);
FORCEPROP 2 LAST CDS_LIB mstr_standard
J 0
(-7450 4775);
DISPLAY 0.723404 (-7450 4775);
PAINT MONO (-7450 4775);
DISPLAY INVISIBLE (-7450 4775);
FORCEPROP 1 LAST BODY_TYPE PLUMBING
J 2
(-7450 4825);
DISPLAY 0.872340 (-7450 4825);
PAINT GREEN (-7450 4825);
DISPLAY INVISIBLE (-7450 4825);
FORCEPROP 1 LAST HDL_TAP TRUE
J 2
(-7775 4650);
DISPLAY 0.872340 (-7775 4650);
DISPLAY INVISIBLE (-7775 4650);
FORCEPROP 1 LAST PATH I85
J 2
(-7448 4775);
DISPLAY 0.872340 (-7448 4775);
PAINT GREEN (-7448 4775);
DISPLAY INVISIBLE (-7448 4775);
FORCEADD TAP..1
R 2
(-7450 4825);
FORCEPROP 3 LASTPIN (-7400 4825) SIG_NAME M_A_CPU1_SB_CA<1>
J 0
(-7390 4835);
DISPLAY 0.659574 (-7390 4835);
PAINT MONO (-7390 4835);
DISPLAY INVISIBLE (-7390 4835);
FORCEPROP 1 LASTPIN (-7400 4825) BN 1
J 2
(-7388 4833);
DISPLAY 0.489362 (-7388 4833);
PAINT GREEN (-7388 4833);
FORCEPROP 2 LAST CDS_LIB mstr_standard
J 0
(-7450 4825);
DISPLAY 0.723404 (-7450 4825);
PAINT MONO (-7450 4825);
DISPLAY INVISIBLE (-7450 4825);
FORCEPROP 1 LAST BODY_TYPE PLUMBING
J 2
(-7450 4875);
DISPLAY 0.872340 (-7450 4875);
PAINT GREEN (-7450 4875);
DISPLAY INVISIBLE (-7450 4875);
FORCEPROP 1 LAST HDL_TAP TRUE
J 2
(-7775 4700);
DISPLAY 0.872340 (-7775 4700);
DISPLAY INVISIBLE (-7775 4700);
FORCEPROP 1 LAST PATH I86
J 2
(-7448 4825);
DISPLAY 0.872340 (-7448 4825);
PAINT GREEN (-7448 4825);
DISPLAY INVISIBLE (-7448 4825);
FORCEADD TAP..1
R 2
(-7450 4875);
FORCEPROP 3 LASTPIN (-7400 4875) SIG_NAME M_A_CPU1_SB_CA<2>
J 0
(-7390 4885);
DISPLAY 0.659574 (-7390 4885);
PAINT MONO (-7390 4885);
DISPLAY INVISIBLE (-7390 4885);
FORCEPROP 1 LASTPIN (-7400 4875) BN 2
J 2
(-7388 4883);
DISPLAY 0.489362 (-7388 4883);
PAINT GREEN (-7388 4883);
FORCEPROP 2 LAST CDS_LIB mstr_standard
J 0
(-7450 4875);
DISPLAY 0.723404 (-7450 4875);
PAINT MONO (-7450 4875);
DISPLAY INVISIBLE (-7450 4875);
FORCEPROP 1 LAST BODY_TYPE PLUMBING
J 2
(-7450 4925);
DISPLAY 0.872340 (-7450 4925);
PAINT GREEN (-7450 4925);
DISPLAY INVISIBLE (-7450 4925);
FORCEPROP 1 LAST HDL_TAP TRUE
J 2
(-7775 4750);
DISPLAY 0.872340 (-7775 4750);
DISPLAY INVISIBLE (-7775 4750);
FORCEPROP 1 LAST PATH I87
J 2
(-7448 4875);
DISPLAY 0.872340 (-7448 4875);
PAINT GREEN (-7448 4875);
DISPLAY INVISIBLE (-7448 4875);
FORCEADD TAP..1
R 2
(-7450 4925);
FORCEPROP 3 LASTPIN (-7400 4925) SIG_NAME M_A_CPU1_SB_CA<3>
J 0
(-7390 4935);
DISPLAY 0.659574 (-7390 4935);
PAINT MONO (-7390 4935);
DISPLAY INVISIBLE (-7390 4935);
FORCEPROP 1 LASTPIN (-7400 4925) BN 3
J 2
(-7388 4933);
DISPLAY 0.489362 (-7388 4933);
PAINT GREEN (-7388 4933);
FORCEPROP 2 LAST CDS_LIB mstr_standard
J 0
(-7450 4925);
DISPLAY 0.723404 (-7450 4925);
PAINT MONO (-7450 4925);
DISPLAY INVISIBLE (-7450 4925);
FORCEPROP 1 LAST BODY_TYPE PLUMBING
J 2
(-7450 4975);
DISPLAY 0.872340 (-7450 4975);
PAINT GREEN (-7450 4975);
DISPLAY INVISIBLE (-7450 4975);
FORCEPROP 1 LAST HDL_TAP TRUE
J 2
(-7775 4800);
DISPLAY 0.872340 (-7775 4800);
DISPLAY INVISIBLE (-7775 4800);
FORCEPROP 1 LAST PATH I88
J 2
(-7448 4925);
DISPLAY 0.872340 (-7448 4925);
PAINT GREEN (-7448 4925);
DISPLAY INVISIBLE (-7448 4925);
FORCEADD TAP..1
R 2
(-7450 4975);
FORCEPROP 3 LASTPIN (-7400 4975) SIG_NAME M_A_CPU1_SB_CA<4>
J 0
(-7390 4985);
DISPLAY 0.659574 (-7390 4985);
PAINT MONO (-7390 4985);
DISPLAY INVISIBLE (-7390 4985);
FORCEPROP 1 LASTPIN (-7400 4975) BN 4
J 2
(-7388 4983);
DISPLAY 0.489362 (-7388 4983);
PAINT GREEN (-7388 4983);
FORCEPROP 2 LAST CDS_LIB mstr_standard
J 0
(-7450 4975);
DISPLAY 0.723404 (-7450 4975);
PAINT MONO (-7450 4975);
DISPLAY INVISIBLE (-7450 4975);
FORCEPROP 1 LAST BODY_TYPE PLUMBING
J 2
(-7450 5025);
DISPLAY 0.872340 (-7450 5025);
PAINT GREEN (-7450 5025);
DISPLAY INVISIBLE (-7450 5025);
FORCEPROP 1 LAST HDL_TAP TRUE
J 2
(-7775 4850);
DISPLAY 0.872340 (-7775 4850);
DISPLAY INVISIBLE (-7775 4850);
FORCEPROP 1 LAST PATH I89
J 2
(-7448 4975);
DISPLAY 0.872340 (-7448 4975);
PAINT GREEN (-7448 4975);
DISPLAY INVISIBLE (-7448 4975);
FORCEADD OFFPAGE..1
(-8050 3175);
FORCEPROP 2 LAST $XR0 37 
J 0
(-8271 3175);
DISPLAY 0.638298 (-8271 3175);
PAINT MONO (-8271 3175);
FORCEPROP 2 LAST CDS_LIB mstr_standard
J 0
(-8050 3175);
DISPLAY 0.808511 (-8050 3175);
DISPLAY INVISIBLE (-8050 3175);
FORCEPROP 1 LAST OFFPAGE TRUE
J 0
(-7725 3050);
DISPLAY 0.872340 (-7725 3050);
PAINT GREEN (-7725 3050);
DISPLAY INVISIBLE (-7725 3050);
FORCEPROP 1 LAST COMMENT_BODY TRUE
J 0
(-7925 3075);
DISPLAY 0.872340 (-7925 3075);
PAINT GREEN (-7925 3075);
DISPLAY INVISIBLE (-7925 3075);
FORCEPROP 2 LAST PATH I9
J 0
(-8300 3225);
DISPLAY 1.021277 (-8300 3225);
DISPLAY INVISIBLE (-8300 3225);
FORCEADD TAP..1
R 2
(-7450 5025);
FORCEPROP 3 LASTPIN (-7400 5025) SIG_NAME M_A_CPU1_SB_CA<5>
J 0
(-7390 5035);
DISPLAY 0.659574 (-7390 5035);
PAINT MONO (-7390 5035);
DISPLAY INVISIBLE (-7390 5035);
FORCEPROP 1 LASTPIN (-7400 5025) BN 5
J 2
(-7388 5033);
DISPLAY 0.489362 (-7388 5033);
PAINT GREEN (-7388 5033);
FORCEPROP 2 LAST CDS_LIB mstr_standard
J 0
(-7450 5025);
DISPLAY 0.723404 (-7450 5025);
PAINT MONO (-7450 5025);
DISPLAY INVISIBLE (-7450 5025);
FORCEPROP 1 LAST BODY_TYPE PLUMBING
J 2
(-7450 5075);
DISPLAY 0.872340 (-7450 5075);
PAINT GREEN (-7450 5075);
DISPLAY INVISIBLE (-7450 5075);
FORCEPROP 1 LAST HDL_TAP TRUE
J 2
(-7775 4900);
DISPLAY 0.872340 (-7775 4900);
DISPLAY INVISIBLE (-7775 4900);
FORCEPROP 1 LAST PATH I90
J 2
(-7448 5025);
DISPLAY 0.872340 (-7448 5025);
PAINT GREEN (-7448 5025);
DISPLAY INVISIBLE (-7448 5025);
FORCEADD TAP..1
R 2
(-7450 5075);
FORCEPROP 3 LASTPIN (-7400 5075) SIG_NAME M_A_CPU1_SB_CA<6>
J 0
(-7390 5085);
DISPLAY 0.659574 (-7390 5085);
PAINT MONO (-7390 5085);
DISPLAY INVISIBLE (-7390 5085);
FORCEPROP 1 LASTPIN (-7400 5075) BN 6
J 2
(-7388 5083);
DISPLAY 0.489362 (-7388 5083);
PAINT GREEN (-7388 5083);
FORCEPROP 2 LAST CDS_LIB mstr_standard
J 0
(-7450 5075);
DISPLAY 0.723404 (-7450 5075);
PAINT MONO (-7450 5075);
DISPLAY INVISIBLE (-7450 5075);
FORCEPROP 1 LAST BODY_TYPE PLUMBING
J 2
(-7450 5125);
DISPLAY 0.872340 (-7450 5125);
PAINT GREEN (-7450 5125);
DISPLAY INVISIBLE (-7450 5125);
FORCEPROP 1 LAST HDL_TAP TRUE
J 2
(-7775 4950);
DISPLAY 0.872340 (-7775 4950);
DISPLAY INVISIBLE (-7775 4950);
FORCEPROP 1 LAST PATH I91
J 2
(-7448 5075);
DISPLAY 0.872340 (-7448 5075);
PAINT GREEN (-7448 5075);
DISPLAY INVISIBLE (-7448 5075);
FORCEADD TAP..1
R 2
(-7450 5225);
FORCEPROP 3 LASTPIN (-7400 5225) SIG_NAME M_A_CPU1_SA_CA<1>
J 0
(-7390 5235);
DISPLAY 0.659574 (-7390 5235);
PAINT MONO (-7390 5235);
DISPLAY INVISIBLE (-7390 5235);
FORCEPROP 1 LASTPIN (-7400 5225) BN 1
J 2
(-7388 5233);
DISPLAY 0.489362 (-7388 5233);
PAINT GREEN (-7388 5233);
FORCEPROP 2 LAST CDS_LIB mstr_standard
J 0
(-7450 5225);
DISPLAY 0.723404 (-7450 5225);
PAINT MONO (-7450 5225);
DISPLAY INVISIBLE (-7450 5225);
FORCEPROP 1 LAST BODY_TYPE PLUMBING
J 2
(-7450 5275);
DISPLAY 0.872340 (-7450 5275);
PAINT GREEN (-7450 5275);
DISPLAY INVISIBLE (-7450 5275);
FORCEPROP 1 LAST HDL_TAP TRUE
J 2
(-7775 5100);
DISPLAY 0.872340 (-7775 5100);
DISPLAY INVISIBLE (-7775 5100);
FORCEPROP 1 LAST PATH I92
J 2
(-7448 5225);
DISPLAY 0.872340 (-7448 5225);
PAINT GREEN (-7448 5225);
DISPLAY INVISIBLE (-7448 5225);
FORCEADD TAP..1
R 2
(-7450 5175);
FORCEPROP 3 LASTPIN (-7400 5175) SIG_NAME M_A_CPU1_SA_CA<0>
J 0
(-7390 5185);
DISPLAY 0.659574 (-7390 5185);
PAINT MONO (-7390 5185);
DISPLAY INVISIBLE (-7390 5185);
FORCEPROP 1 LASTPIN (-7400 5175) BN 0
J 2
(-7388 5183);
DISPLAY 0.489362 (-7388 5183);
PAINT GREEN (-7388 5183);
FORCEPROP 2 LAST CDS_LIB mstr_standard
J 0
(-7450 5175);
DISPLAY 0.723404 (-7450 5175);
PAINT MONO (-7450 5175);
DISPLAY INVISIBLE (-7450 5175);
FORCEPROP 1 LAST BODY_TYPE PLUMBING
J 2
(-7450 5225);
DISPLAY 0.872340 (-7450 5225);
PAINT GREEN (-7450 5225);
DISPLAY INVISIBLE (-7450 5225);
FORCEPROP 1 LAST HDL_TAP TRUE
J 2
(-7775 5050);
DISPLAY 0.872340 (-7775 5050);
DISPLAY INVISIBLE (-7775 5050);
FORCEPROP 1 LAST PATH I93
J 2
(-7448 5175);
DISPLAY 0.872340 (-7448 5175);
PAINT GREEN (-7448 5175);
DISPLAY INVISIBLE (-7448 5175);
FORCEADD TAP..1
R 2
(-7450 5275);
FORCEPROP 3 LASTPIN (-7400 5275) SIG_NAME M_A_CPU1_SA_CA<2>
J 0
(-7390 5285);
DISPLAY 0.659574 (-7390 5285);
PAINT MONO (-7390 5285);
DISPLAY INVISIBLE (-7390 5285);
FORCEPROP 1 LASTPIN (-7400 5275) BN 2
J 2
(-7388 5283);
DISPLAY 0.489362 (-7388 5283);
PAINT GREEN (-7388 5283);
FORCEPROP 2 LAST CDS_LIB mstr_standard
J 0
(-7450 5275);
DISPLAY 0.723404 (-7450 5275);
PAINT MONO (-7450 5275);
DISPLAY INVISIBLE (-7450 5275);
FORCEPROP 1 LAST BODY_TYPE PLUMBING
J 2
(-7450 5325);
DISPLAY 0.872340 (-7450 5325);
PAINT GREEN (-7450 5325);
DISPLAY INVISIBLE (-7450 5325);
FORCEPROP 1 LAST HDL_TAP TRUE
J 2
(-7775 5150);
DISPLAY 0.872340 (-7775 5150);
DISPLAY INVISIBLE (-7775 5150);
FORCEPROP 1 LAST PATH I94
J 2
(-7448 5275);
DISPLAY 0.872340 (-7448 5275);
PAINT GREEN (-7448 5275);
DISPLAY INVISIBLE (-7448 5275);
FORCEADD TAP..1
R 2
(-7450 5325);
FORCEPROP 3 LASTPIN (-7400 5325) SIG_NAME M_A_CPU1_SA_CA<3>
J 0
(-7390 5335);
DISPLAY 0.659574 (-7390 5335);
PAINT MONO (-7390 5335);
DISPLAY INVISIBLE (-7390 5335);
FORCEPROP 1 LASTPIN (-7400 5325) BN 3
J 2
(-7388 5333);
DISPLAY 0.489362 (-7388 5333);
PAINT GREEN (-7388 5333);
FORCEPROP 2 LAST CDS_LIB mstr_standard
J 0
(-7450 5325);
DISPLAY 0.723404 (-7450 5325);
PAINT MONO (-7450 5325);
DISPLAY INVISIBLE (-7450 5325);
FORCEPROP 1 LAST BODY_TYPE PLUMBING
J 2
(-7450 5375);
DISPLAY 0.872340 (-7450 5375);
PAINT GREEN (-7450 5375);
DISPLAY INVISIBLE (-7450 5375);
FORCEPROP 1 LAST HDL_TAP TRUE
J 2
(-7775 5200);
DISPLAY 0.872340 (-7775 5200);
DISPLAY INVISIBLE (-7775 5200);
FORCEPROP 1 LAST PATH I95
J 2
(-7448 5325);
DISPLAY 0.872340 (-7448 5325);
PAINT GREEN (-7448 5325);
DISPLAY INVISIBLE (-7448 5325);
FORCEADD TAP..1
R 2
(-7450 5375);
FORCEPROP 3 LASTPIN (-7400 5375) SIG_NAME M_A_CPU1_SA_CA<4>
J 0
(-7390 5385);
DISPLAY 0.659574 (-7390 5385);
PAINT MONO (-7390 5385);
DISPLAY INVISIBLE (-7390 5385);
FORCEPROP 1 LASTPIN (-7400 5375) BN 4
J 2
(-7388 5383);
DISPLAY 0.489362 (-7388 5383);
PAINT GREEN (-7388 5383);
FORCEPROP 2 LAST CDS_LIB mstr_standard
J 0
(-7450 5375);
DISPLAY 0.723404 (-7450 5375);
PAINT MONO (-7450 5375);
DISPLAY INVISIBLE (-7450 5375);
FORCEPROP 1 LAST BODY_TYPE PLUMBING
J 2
(-7450 5425);
DISPLAY 0.872340 (-7450 5425);
PAINT GREEN (-7450 5425);
DISPLAY INVISIBLE (-7450 5425);
FORCEPROP 1 LAST HDL_TAP TRUE
J 2
(-7775 5250);
DISPLAY 0.872340 (-7775 5250);
DISPLAY INVISIBLE (-7775 5250);
FORCEPROP 1 LAST PATH I96
J 2
(-7448 5375);
DISPLAY 0.872340 (-7448 5375);
PAINT GREEN (-7448 5375);
DISPLAY INVISIBLE (-7448 5375);
FORCEADD TAP..1
R 2
(-7450 5425);
FORCEPROP 3 LASTPIN (-7400 5425) SIG_NAME M_A_CPU1_SA_CA<5>
J 0
(-7390 5435);
DISPLAY 0.659574 (-7390 5435);
PAINT MONO (-7390 5435);
DISPLAY INVISIBLE (-7390 5435);
FORCEPROP 1 LASTPIN (-7400 5425) BN 5
J 2
(-7388 5433);
DISPLAY 0.489362 (-7388 5433);
PAINT GREEN (-7388 5433);
FORCEPROP 2 LAST CDS_LIB mstr_standard
J 0
(-7450 5425);
DISPLAY 0.723404 (-7450 5425);
PAINT MONO (-7450 5425);
DISPLAY INVISIBLE (-7450 5425);
FORCEPROP 1 LAST BODY_TYPE PLUMBING
J 2
(-7450 5475);
DISPLAY 0.872340 (-7450 5475);
PAINT GREEN (-7450 5475);
DISPLAY INVISIBLE (-7450 5475);
FORCEPROP 1 LAST HDL_TAP TRUE
J 2
(-7775 5300);
DISPLAY 0.872340 (-7775 5300);
DISPLAY INVISIBLE (-7775 5300);
FORCEPROP 1 LAST PATH I97
J 2
(-7448 5425);
DISPLAY 0.872340 (-7448 5425);
PAINT GREEN (-7448 5425);
DISPLAY INVISIBLE (-7448 5425);
FORCEADD TAP..1
R 2
(-7450 5475);
FORCEPROP 3 LASTPIN (-7400 5475) SIG_NAME M_A_CPU1_SA_CA<6>
J 0
(-7390 5485);
DISPLAY 0.659574 (-7390 5485);
PAINT MONO (-7390 5485);
DISPLAY INVISIBLE (-7390 5485);
FORCEPROP 1 LASTPIN (-7400 5475) BN 6
J 2
(-7388 5483);
DISPLAY 0.489362 (-7388 5483);
PAINT GREEN (-7388 5483);
FORCEPROP 2 LAST CDS_LIB mstr_standard
J 0
(-7450 5475);
DISPLAY 0.723404 (-7450 5475);
PAINT MONO (-7450 5475);
DISPLAY INVISIBLE (-7450 5475);
FORCEPROP 1 LAST BODY_TYPE PLUMBING
J 2
(-7450 5525);
DISPLAY 0.872340 (-7450 5525);
PAINT GREEN (-7450 5525);
DISPLAY INVISIBLE (-7450 5525);
FORCEPROP 1 LAST HDL_TAP TRUE
J 2
(-7775 5350);
DISPLAY 0.872340 (-7775 5350);
DISPLAY INVISIBLE (-7775 5350);
FORCEPROP 1 LAST PATH I98
J 2
(-7448 5475);
DISPLAY 0.872340 (-7448 5475);
PAINT GREEN (-7448 5475);
DISPLAY INVISIBLE (-7448 5475);
FORCEADD TAP..1
(-5750 4225);
FORCEPROP 3 LASTPIN (-5800 4225) SIG_NAME M_A_CPU1_SA_DQ<6>
J 0
(-5790 4235);
DISPLAY 0.659574 (-5790 4235);
PAINT MONO (-5790 4235);
DISPLAY INVISIBLE (-5790 4235);
FORCEPROP 1 LASTPIN (-5800 4225) BN 6
J 0
(-5812 4233);
DISPLAY 0.489362 (-5812 4233);
PAINT GREEN (-5812 4233);
FORCEPROP 2 LAST CDS_LIB mstr_standard
J 0
(-5750 4225);
DISPLAY 0.723404 (-5750 4225);
PAINT MONO (-5750 4225);
DISPLAY INVISIBLE (-5750 4225);
FORCEPROP 1 LAST BODY_TYPE PLUMBING
J 0
(-5750 4275);
DISPLAY 0.872340 (-5750 4275);
PAINT GREEN (-5750 4275);
DISPLAY INVISIBLE (-5750 4275);
FORCEPROP 1 LAST HDL_TAP TRUE
J 0
(-5425 4100);
DISPLAY 0.872340 (-5425 4100);
DISPLAY INVISIBLE (-5425 4100);
FORCEPROP 1 LAST PATH I99
J 0
(-5752 4225);
DISPLAY 0.872340 (-5752 4225);
PAINT GREEN (-5752 4225);
DISPLAY INVISIBLE (-5752 4225);
FORCEADD DNS..2
(-8625 2400);
PAINT RED (-8625 2400);
FORCEPROP 2 LAST CDS_LIB mstr_misc
J 0
(-8625 2400);
DISPLAY INVISIBLE (-8625 2400);
FORCEPROP 1 LAST COMMENT_BODY TRUE
R 1
J 0
(-8550 2175);
DISPLAY 0.872340 (-8550 2175);
PAINT PEACH (-8550 2175);
DISPLAY INVISIBLE (-8550 2175);
FORCEADD DNS..2
(-8250 2375);
PAINT RED (-8250 2375);
FORCEPROP 2 LAST CDS_LIB mstr_misc
J 0
(-8250 2375);
DISPLAY INVISIBLE (-8250 2375);
FORCEPROP 1 LAST COMMENT_BODY TRUE
R 1
J 0
(-8175 2150);
DISPLAY 0.872340 (-8175 2150);
PAINT PEACH (-8175 2150);
DISPLAY INVISIBLE (-8175 2150);
FORCEADD QUANTA_TITLE_BLOCK_C..1
(-100 100);
FORCEPROP 0 LAST CDS_CON_LAST_MODIFIED Thu Sep 14 16:12:09 2023
J 0
(-1985 115);
DISPLAY INVISIBLE (-1985 115);
FORCEPROP 1 LAST CUSTOM_TXT_CDS <CON_LAST_MODIFIED>
J 0
(-1985 115);
DISPLAY 0.978723 (-1985 115);
FORCEPROP 2 LAST CUSTOM_TXT_CDS <XR_PAGE_TITLE>
J 0
(-7990 5350);
DISPLAY 0.638298 (-7990 5350);
PAINT PINK (-7990 5350);
DISPLAY INVISIBLE (-7990 5350);
FORCEPROP 1 LAST CUSTOM_TXT_CDS <NAME_2>
J 0
(-3275 150);
FORCEPROP 1 LAST CUSTOM_TXT_CDS <NAME_1>
J 0
(-3275 275);
FORCEPROP 1 LAST CUSTOM_TXT_CDS <Q_NUMBER>
J 0
(-1503 203);
DISPLAY 1.212766 (-1503 203);
FORCEPROP 1 LAST CUSTOM_TXT_CDS <Q_PROJ>
J 0
(-2482 202);
DISPLAY 1.212766 (-2482 202);
FORCEPROP 1 LAST CUSTOM_TXT_CDS <Q_REV>
J 0
(-284 203);
DISPLAY 1.212766 (-284 203);
FORCEPROP 1 LAST CUSTOM_TXT_CDS <CON_PAGE_NUM> OF <CON_TOTAL_PAGES>
J 0
(-546 118);
DISPLAY 0.978723 (-546 118);
FORCEPROP 1 LAST Q_TITLE DDR5 - CPU1 CHA
J 0
(-9400 150);
DISPLAY 2.446809 (-9400 150);
PAINT GREEN (-9400 150);
FORCEPROP 2 LAST CDS_LIB pure_quanta
J 0
(-100 100);
DISPLAY INVISIBLE (-100 100);
FORCEPROP 1 LAST CDS_LMAN_SYM_OUTLINE -9475,6775,100,-125
J 0
(-100 100);
DISPLAY 0.468085 (-100 100);
PAINT GREEN (-100 100);
DISPLAY INVISIBLE (-100 100);
FORCEPROP 2 LAST PAGE_BORDER TRUE
J 0
(-7990 5350);
DISPLAY 0.638298 (-7990 5350);
PAINT PINK (-7990 5350);
DISPLAY INVISIBLE (-7990 5350);
FORCEPROP 2 LAST CDS_XR_PAGE_TITLE CR-98 : @T6G_MB_LIB.T6G(SCH_1):PAGE98
J 0
(-7990 5350);
DISPLAY 0.638298 (-7990 5350);
PAINT PINK (-7990 5350);
DISPLAY INVISIBLE (-7990 5350);
FORCEPROP 1 LAST Q_DEPT BU9
J 1
(-3863 149);
DISPLAY 1.957447 (-3863 149);
PAINT GREEN (-3863 149);
DISPLAY INVISIBLE (-3863 149);
FORCEPROP 1 LAST COMMENT_BODY TRUE
J 0
(-88 87);
DISPLAY 0.978723 (-88 87);
PAINT GREEN (-88 87);
DISPLAY INVISIBLE (-88 87);
FORCEADD DNS..2
(-2450 1500);
PAINT RED (-2450 1500);
FORCEPROP 2 LAST CDS_LIB mstr_misc
J 0
(-2450 1500);
DISPLAY INVISIBLE (-2450 1500);
FORCEPROP 1 LAST COMMENT_BODY TRUE
R 1
J 0
(-2375 1275);
DISPLAY 0.872340 (-2375 1275);
PAINT PEACH (-2375 1275);
DISPLAY INVISIBLE (-2375 1275);
FORCEADD DNS..2
(-4400 1350);
PAINT RED (-4400 1350);
FORCEPROP 2 LAST CDS_LIB mstr_misc
J 0
(-4400 1350);
DISPLAY INVISIBLE (-4400 1350);
FORCEPROP 1 LAST COMMENT_BODY TRUE
R 1
J 0
(-4325 1125);
DISPLAY 0.872340 (-4325 1125);
PAINT PEACH (-4325 1125);
DISPLAY INVISIBLE (-4325 1125);
WIRE 17 -1 (-5700 2450)(-5700 2500);
WIRE 17 -1 (-5700 2400)(-5700 2450);
WIRE 17 -1 (-5700 2550)(-5700 2500);
WIRE 17 -1 (-5700 2600)(-5700 2550);
WIRE 17 -1 (-5700 2350)(-5700 2400);
WIRE 17 -1 (-5700 2300)(-5700 2350);
WIRE 17 -1 (-5700 2650)(-5700 2600);
WIRE 17 -1 (-5700 2700)(-5700 2650);
WIRE 17 -1 (-5700 2750)(-5700 2700);
WIRE 17 -1 (-5700 2800)(-5700 2750);
WIRE 17 -1 (-5700 2850)(-5700 2800);
WIRE 17 -1 (-5700 2900)(-5700 2850);
WIRE 17 -1 (-5700 2900)(-5700 2950);
WIRE 17 -1 (-5700 2950)(-5700 3000);
WIRE 17 -1 (-5700 3000)(-5700 3050);
WIRE 17 -1 (-5700 3050)(-5700 3100);
WIRE 17 -1 (-5700 3150)(-5700 3100);
WIRE 17 -1 (-5700 3200)(-5700 3150);
WIRE 17 -1 (-5700 3250)(-5700 3200);
WIRE 17 -1 (-5700 3300)(-5700 3250);
WIRE 17 -1 (-5700 3350)(-5700 3300);
WIRE 17 -1 (-5700 3400)(-5700 3350);
WIRE 17 -1 (-5700 3450)(-5700 3400);
WIRE 17 -1 (-5700 3500)(-5700 3450);
WIRE 17 -1 (-5700 3550)(-5700 3500);
WIRE 17 -1 (-5700 3600)(-5700 3550);
WIRE 17 -1 (-5700 3650)(-5700 3600);
WIRE 17 -1 (-5700 3700)(-5700 3650);
WIRE 17 -1 (-5700 3750)(-5700 3700);
WIRE 17 -1 (-5700 3800)(-5700 3750);
WIRE 17 -1 (-5700 3850)(-5700 3800);
WIRE 17 -1 (-5700 3875)(-5700 3850);
WIRE 17 -1 (-5700 3875)(-5200 3875);
FORCEPROP 2 LAST SIG_NAME M_A_CPU1_SB_DQ<31:0>
J 2
(-5200 3885);
DISPLAY 0.489362 (-5200 3885);
WIRE 17 -1 (-7500 5500)(-7500 5525);
WIRE 17 -1 (-7500 5450)(-7500 5500);
WIRE 17 -1 (-7500 5525)(-8000 5525);
FORCEPROP 2 LAST SIG_NAME M_A_CPU1_SA_CA<6:0>
J 0
(-8000 5535);
DISPLAY 0.489362 (-8000 5535);
WIRE 17 -1 (-7500 5350)(-7500 5400);
WIRE 17 -1 (-7500 5300)(-7500 5350);
WIRE 17 -1 (-7500 5400)(-7500 5450);
WIRE 17 -1 (-7500 5250)(-7500 5300);
WIRE 17 -1 (-7500 5200)(-7500 5250);
WIRE 17 -1 (-3175 4650)(-3175 4625);
WIRE 17 -1 (-3175 4650)(-2475 4650);
FORCEPROP 2 LAST SIG_NAME M_A_CPU1_SA_DQS_DP<9:0>
J 0
(-3010 4660);
DISPLAY 0.489362 (-3010 4660);
WIRE 17 -1 (-5700 5050)(-5700 5000);
WIRE 17 -1 (-5700 5100)(-5700 5050);
WIRE 17 -1 (-5700 5000)(-5700 4950);
WIRE 17 -1 (-5700 4950)(-5700 4900);
WIRE 17 -1 (-5700 5150)(-5700 5100);
WIRE 17 -1 (-5700 5200)(-5700 5150);
WIRE 17 -1 (-5700 4900)(-5700 4850);
WIRE 17 -1 (-5700 4850)(-5700 4800);
WIRE 17 -1 (-5700 5250)(-5700 5200);
WIRE 17 -1 (-5700 5300)(-5700 5250);
WIRE 17 -1 (-5700 4800)(-5700 4750);
WIRE 17 -1 (-5700 4700)(-5700 4750);
WIRE 17 -1 (-5700 5350)(-5700 5300);
WIRE 17 -1 (-5700 5400)(-5700 5350);
WIRE 17 -1 (-5700 4650)(-5700 4700);
WIRE 17 -1 (-5700 4600)(-5700 4650);
WIRE 17 -1 (-5700 5450)(-5700 5400);
WIRE 17 -1 (-5700 5500)(-5700 5450);
WIRE 17 -1 (-5700 4550)(-5700 4600);
WIRE 17 -1 (-5700 4550)(-5700 4500);
WIRE 17 -1 (-5700 5525)(-5700 5500);
WIRE 17 -1 (-5700 5525)(-5200 5525);
FORCEPROP 2 LAST SIG_NAME M_A_CPU1_SA_DQ<31:0>
J 2
(-5200 5535);
DISPLAY 0.489362 (-5200 5535);
WIRE 17 -1 (-3175 3600)(-3175 3575);
WIRE 17 -1 (-3175 3600)(-2475 3600);
FORCEPROP 2 LAST SIG_NAME M_A_CPU1_SB_DQS_DP<9:0>
J 2
(-2475 3610);
DISPLAY 0.489362 (-2475 3610);
WIRE 17 -1 (-2975 3550)(-2975 3525);
WIRE 17 -1 (-2975 3550)(-2475 3550);
FORCEPROP 2 LAST SIG_NAME M_A_CPU1_SB_DQS_DN<9:0>
J 2
(-2475 3560);
DISPLAY 0.489362 (-2475 3560);
WIRE 17 -1 (-2975 4600)(-2975 4575);
WIRE 17 -1 (-2975 4600)(-2475 4600);
FORCEPROP 2 LAST SIG_NAME M_A_CPU1_SA_DQS_DN<9:0>
J 0
(-3010 4610);
DISPLAY 0.489362 (-3010 4610);
WIRE 17 -1 (-3175 4625)(-3175 4525);
WIRE 17 -1 (-3175 4525)(-3175 4425);
WIRE 17 -1 (-3175 4425)(-3175 4325);
WIRE 17 -1 (-2975 4575)(-2975 4475);
WIRE 17 -1 (-2975 4475)(-2975 4375);
WIRE 17 -1 (-2975 4375)(-2975 4275);
WIRE 17 -1 (-2975 3425)(-2975 3325);
WIRE 17 -1 (-2975 3525)(-2975 3425);
WIRE 17 -1 (-2975 3325)(-2975 3225);
WIRE 17 -1 (-2975 3225)(-2975 3125);
WIRE 17 -1 (-3175 4325)(-3175 4225);
WIRE 17 -1 (-3175 3375)(-3175 3275);
WIRE 17 -1 (-3175 3475)(-3175 3375);
WIRE 17 -1 (-3175 3275)(-3175 3175);
WIRE 17 -1 (-3175 3075)(-3175 3175);
WIRE 17 -1 (-3175 3575)(-3175 3475);
WIRE 17 -1 (-3175 2975)(-3175 3075);
WIRE 17 -1 (-3175 2875)(-3175 2975);
WIRE 17 -1 (-2975 3025)(-2975 3125);
WIRE 17 -1 (-2975 2925)(-2975 3025);
WIRE 17 -1 (-2975 2825)(-2975 2925);
WIRE 17 -1 (-2975 4275)(-2975 4175);
WIRE 17 -1 (-2975 4075)(-2975 4175);
WIRE 17 -1 (-2975 3975)(-2975 4075);
WIRE 17 -1 (-2975 3875)(-2975 3975);
WIRE 17 -1 (-3175 2875)(-3175 2775);
WIRE 17 -1 (-2975 2825)(-2975 2725);
WIRE 17 -1 (-3175 4125)(-3175 4225);
WIRE 17 -1 (-3175 4025)(-3175 4125);
WIRE 17 -1 (-3175 3925)(-3175 4025);
WIRE 17 -1 (-3175 3925)(-3175 3825);
WIRE 17 -1 (-2975 3875)(-2975 3775);
WIRE 17 -1 (-3175 2775)(-3175 2675);
WIRE 17 -1 (-2975 2725)(-2975 2625);
WIRE 17 -1 (-3175 3825)(-3175 3725);
WIRE 17 -1 (-2975 3775)(-2975 3675);
WIRE 17 -1 (-5700 4500)(-5700 4450);
WIRE 17 -1 (-5700 4450)(-5700 4400);
WIRE 17 -1 (-5700 4400)(-5700 4350);
WIRE 17 -1 (-5700 4350)(-5700 4300);
WIRE 17 -1 (-5700 4300)(-5700 4250);
WIRE 17 -1 (-5700 4250)(-5700 4200);
WIRE 17 -1 (-5700 4200)(-5700 4150);
WIRE 17 -1 (-5700 4100)(-5700 4150);
WIRE 17 -1 (-5700 3950)(-5700 4000);
WIRE 17 -1 (-5700 4000)(-5700 4050);
WIRE 17 -1 (-5700 4050)(-5700 4100);
WIRE 17 -1 (-7500 3300)(-7500 3350);
WIRE 17 -1 (-7500 3350)(-7500 3400);
WIRE 17 -1 (-7500 3400)(-7500 3450);
WIRE 17 -1 (-7500 3450)(-7500 3500);
WIRE 17 -1 (-7500 3550)(-7500 3500);
WIRE 17 -1 (-7500 3550)(-7500 3600);
WIRE 17 -1 (-7500 3650)(-7500 3600);
WIRE 17 -1 (-7500 3650)(-7500 3675);
WIRE 17 -1 (-7500 3675)(-8000 3675);
FORCEPROP 2 LAST SIG_NAME M_A_CPU1_SB_CB<7:0>
J 0
(-8000 3685);
DISPLAY 0.489362 (-8000 3685);
WIRE 17 -1 (-7500 3850)(-7500 3900);
WIRE 17 -1 (-7500 3800)(-7500 3850);
WIRE 17 -1 (-7500 3900)(-7500 3950);
WIRE 17 -1 (-7500 4000)(-7500 3950);
WIRE 17 -1 (-7500 3750)(-7500 3800);
WIRE 17 -1 (-7500 4000)(-7500 4050);
WIRE 17 -1 (-7500 4100)(-7500 4050);
WIRE 17 -1 (-7500 4100)(-7500 4125);
WIRE 17 -1 (-7500 4125)(-8000 4125);
FORCEPROP 2 LAST SIG_NAME M_A_CPU1_SA_CB<7:0>
J 0
(-8000 4135);
DISPLAY 0.489362 (-8000 4135);
WIRE 17 -1 (-7500 5100)(-7500 5125);
WIRE 17 -1 (-7500 5050)(-7500 5100);
WIRE 17 -1 (-7500 5125)(-8000 5125);
FORCEPROP 2 LAST SIG_NAME M_A_CPU1_SB_CA<6:0>
J 0
(-8000 5135);
DISPLAY 0.489362 (-8000 5135);
WIRE 17 -1 (-7500 5000)(-7500 5050);
WIRE 17 -1 (-7500 4950)(-7500 5000);
WIRE 17 -1 (-7500 4900)(-7500 4950);
WIRE 17 -1 (-7500 4850)(-7500 4900);
WIRE 17 -1 (-7500 4800)(-7500 4850);
WIRE 16 -1 (-6125 1125)(-6125 1200);
WIRE 16 -1 (-8600 3150)(-8600 3225);
WIRE 16 -1 (-8525 2475)(-8525 2500);
WIRE 16 -1 (-8275 2475)(-8275 2500);
WIRE 16 -1 (-8950 1550)(-8950 1700);
WIRE 16 -1 (-7200 2025)(-8000 2025);
FORCEPROP 2 LAST SIG_NAME M_A_CPU1_SB_RSP<0>
J 0
(-8000 2035);
DISPLAY 0.489362 (-8000 2035);
WIRE 16 -1 (-8000 2925)(-7975 2925);
WIRE 16 -1 (-8000 2850)(-8000 2925);
WIRE 16 -1 (-8000 2850)(-8500 2850);
FORCEPROP 2 LAST SIG_NAME I3C_SPD_DDRAF_CPU1_SDA
J 0
(-8510 2860);
DISPLAY 0.489362 (-8510 2860);
WIRE 16 -1 (-7200 2925)(-7775 2925);
FORCEPROP 2 LAST SIG_NAME I3C_SPD_DDRA_CPU1_SDA
J 0
(-7685 2935);
DISPLAY 0.446809 (-7685 2935);
FORCEPROP 2 LASTPROP $XRERR UNIQUE?
J 0
(-7925 2935);
DISPLAY 0.638298 (-7925 2935);
PAINT MONO (-7925 2935);
DISPLAY INVISIBLE (-7925 2935);
WIRE 16 -1 (-7575 2725)(-8050 2725);
FORCEPROP 2 LAST SIG_NAME I3C_SPD_DDRAF_CPU1_SCL
J 0
(-8110 2735);
DISPLAY 0.489362 (-8110 2735);
WIRE 16 -1 (-8275 2275)(-8275 2225);
WIRE 16 -1 (-8075 2225)(-8275 2225);
WIRE 16 -1 (-8275 2225)(-8300 2225);
WIRE 16 -1 (-8075 2225)(-8075 2625);
WIRE 16 -1 (-7200 2625)(-8075 2625);
FORCEPROP 2 LAST SIG_NAME PWRGD_CHA_CPU1_DIMM0
J 0
(-7850 2635);
DISPLAY 0.489362 (-7850 2635);
FORCEPROP 2 LASTPROP $XRERR UNIQUE?
J 0
(-8090 2635);
DISPLAY 0.638298 (-8090 2635);
PAINT MONO (-8090 2635);
DISPLAY INVISIBLE (-8090 2635);
WIRE 16 -1 (-7200 2975)(-8125 2975);
FORCEPROP 2 LAST SIG_NAME PD_CHA_CPU1_DIMM0_SAA
J 0
(-8125 2985);
DISPLAY 0.489362 (-8125 2985);
WIRE 16 -1 (-8600 3425)(-8600 3450);
WIRE 16 -1 (-8600 3450)(-8500 3450);
WIRE 16 -1 (-8500 3500)(-8500 3450);
WIRE 16 -1 (-8500 3450)(-8500 3025);
WIRE 16 -1 (-8500 3025)(-7200 3025);
WIRE 16 -1 (-7200 3125)(-8000 3125);
FORCEPROP 2 LAST SIG_NAME M_A_CPU1_ALERT_N
J 0
(-7985 3135);
DISPLAY 0.489362 (-7985 3135);
WIRE 16 -1 (-7200 2875)(-7300 2875);
FORCEPROP 2 LAST SIG_NAME I3C_SPD_DDRA_CPU1_SCL
J 0
(-7685 2885);
DISPLAY 0.446809 (-7685 2885);
FORCEPROP 2 LASTPROP $XRERR UNIQUE?
J 0
(-7925 2885);
DISPLAY 0.638298 (-7925 2885);
PAINT MONO (-7925 2885);
DISPLAY INVISIBLE (-7925 2885);
WIRE 16 -1 (-7300 2875)(-7300 2725);
WIRE 16 -1 (-7300 2725)(-7375 2725);
WIRE 16 -1 (-7200 3175)(-8000 3175);
FORCEPROP 2 LAST SIG_NAME M_A_CPU1_RESET_N
J 0
(-7985 3185);
DISPLAY 0.489362 (-7985 3185);
WIRE 16 -1 (-7200 3625)(-7400 3625);
WIRE 16 -1 (-7200 3725)(-7400 3725);
WIRE 16 -1 (-7200 3775)(-7400 3775);
WIRE 16 -1 (-7200 3425)(-7400 3425);
WIRE 16 -1 (-7200 3475)(-7400 3475);
WIRE 16 -1 (-7200 3525)(-7400 3525);
WIRE 16 -1 (-7200 3575)(-7400 3575);
WIRE 16 -1 (-5800 3775)(-6000 3775);
WIRE 16 -1 (-5800 3725)(-6000 3725);
WIRE 16 -1 (-7200 4475)(-8000 4475);
FORCEPROP 2 LAST SIG_NAME M_A_CPU1_SA_CS_N<0>
J 0
(-8000 4485);
DISPLAY 0.489362 (-8000 4485);
WIRE 16 -1 (-4325 1400)(-3750 1400);
WIRE 16 -1 (-3750 1400)(-3750 925);
WIRE 16 -1 (-3750 925)(-2775 925);
FORCEPROP 2 LAST SIG_NAME PWRGD_CHAF_CPU1_R1
J 0
(-3585 960);
DISPLAY 0.680851 (-3585 960);
FORCEPROP 2 LASTPROP $XRERR UNIQUE?
J 0
(-3825 960);
DISPLAY 0.638298 (-3825 960);
PAINT MONO (-3825 960);
DISPLAY INVISIBLE (-3825 960);
WIRE 16 -1 (-3900 925)(-3750 925);
WIRE 16 -1 (-2775 1375)(-2775 925);
WIRE 16 -1 (-2775 925)(-2675 925);
WIRE 16 -1 (-2600 1375)(-2775 1375);
WIRE 16 -1 (-8950 1050)(-7975 1050);
FORCEPROP 2 LAST SIG_NAME PWRGD_CHAF_CPU1
J 0
(-8810 1060);
DISPLAY 0.680851 (-8810 1060);
WIRE 16 -1 (-8950 1350)(-8950 1050);
WIRE 16 -1 (-4850 925)(-4100 925);
FORCEPROP 2 LAST SIG_NAME PWRGD_CHAF_CPU1
J 0
(-4760 935);
DISPLAY 0.680851 (-4760 935);
WIRE 16 -1 (-1900 2275)(-2100 2275);
WIRE 16 -1 (-2100 2325)(-2100 2275);
WIRE 16 -1 (-2100 2275)(-2100 2225);
WIRE 16 -1 (-1900 2225)(-2100 2225);
WIRE 16 -1 (-2100 2225)(-2100 2125);
WIRE 16 -1 (-1900 2325)(-2100 2325);
WIRE 16 -1 (-2100 2375)(-2100 2325);
WIRE 16 -1 (-1900 2375)(-2100 2375);
WIRE 16 -1 (-2100 2425)(-2100 2375);
WIRE 16 -1 (-1900 2425)(-2100 2425);
WIRE 16 -1 (-2100 2475)(-2100 2425);
WIRE 16 -1 (-1900 2475)(-2100 2475);
WIRE 16 -1 (-2100 2525)(-2100 2475);
WIRE 16 -1 (-1900 2525)(-2100 2525);
WIRE 16 -1 (-2100 2575)(-2100 2525);
WIRE 16 -1 (-1900 2575)(-2100 2575);
WIRE 16 -1 (-2100 2625)(-2100 2575);
WIRE 16 -1 (-1900 2625)(-2100 2625);
WIRE 16 -1 (-2100 2675)(-2100 2625);
WIRE 16 -1 (-1900 2675)(-2100 2675);
WIRE 16 -1 (-2100 2725)(-2100 2675);
WIRE 16 -1 (-1900 2725)(-2100 2725);
WIRE 16 -1 (-2100 2775)(-2100 2725);
WIRE 16 -1 (-1900 2775)(-2100 2775);
WIRE 16 -1 (-2100 2825)(-2100 2775);
WIRE 16 -1 (-1900 2825)(-2100 2825);
WIRE 16 -1 (-2100 2875)(-2100 2825);
WIRE 16 -1 (-1900 2875)(-2100 2875);
WIRE 16 -1 (-2100 2925)(-2100 2875);
WIRE 16 -1 (-1900 2925)(-2100 2925);
WIRE 16 -1 (-2100 2975)(-2100 2925);
WIRE 16 -1 (-1900 2975)(-2100 2975);
WIRE 16 -1 (-2100 3025)(-2100 2975);
WIRE 16 -1 (-1900 3025)(-2100 3025);
WIRE 16 -1 (-2100 3075)(-2100 3025);
WIRE 16 -1 (-1900 3075)(-2100 3075);
WIRE 16 -1 (-2100 3125)(-2100 3075);
WIRE 16 -1 (-1900 3125)(-2100 3125);
WIRE 16 -1 (-2100 3175)(-2100 3125);
WIRE 16 -1 (-1900 3175)(-2100 3175);
WIRE 16 -1 (-2100 3225)(-2100 3175);
WIRE 16 -1 (-1900 3225)(-2100 3225);
WIRE 16 -1 (-2100 3275)(-2100 3225);
WIRE 16 -1 (-1900 3275)(-2100 3275);
WIRE 16 -1 (-2100 3325)(-2100 3275);
WIRE 16 -1 (-1900 3325)(-2100 3325);
WIRE 16 -1 (-2100 3375)(-2100 3325);
WIRE 16 -1 (-1900 3375)(-2100 3375);
WIRE 16 -1 (-2100 3425)(-2100 3375);
WIRE 16 -1 (-1900 3425)(-2100 3425);
WIRE 16 -1 (-2100 3475)(-2100 3425);
WIRE 16 -1 (-1900 3475)(-2100 3475);
WIRE 16 -1 (-2100 3525)(-2100 3475);
WIRE 16 -1 (-1900 3525)(-2100 3525);
WIRE 16 -1 (-2100 3575)(-2100 3525);
WIRE 16 -1 (-1900 3575)(-2100 3575);
WIRE 16 -1 (-2100 3625)(-2100 3575);
WIRE 16 -1 (-1900 3625)(-2100 3625);
WIRE 16 -1 (-2100 3675)(-2100 3625);
WIRE 16 -1 (-1900 3675)(-2100 3675);
WIRE 16 -1 (-2100 3725)(-2100 3675);
WIRE 16 -1 (-1900 3725)(-2100 3725);
WIRE 16 -1 (-2100 3775)(-2100 3725);
WIRE 16 -1 (-1900 3775)(-2100 3775);
WIRE 16 -1 (-2100 3825)(-2100 3775);
WIRE 16 -1 (-1900 3825)(-2100 3825);
WIRE 16 -1 (-2100 3875)(-2100 3825);
WIRE 16 -1 (-1900 3875)(-2100 3875);
WIRE 16 -1 (-2100 3925)(-2100 3875);
WIRE 16 -1 (-1900 3925)(-2100 3925);
WIRE 16 -1 (-2100 3975)(-2100 3925);
WIRE 16 -1 (-1900 3975)(-2100 3975);
WIRE 16 -1 (-2100 4025)(-2100 3975);
WIRE 16 -1 (-1900 4025)(-2100 4025);
WIRE 16 -1 (-2100 4075)(-2100 4025);
WIRE 16 -1 (-2100 4125)(-2100 4075);
WIRE 16 -1 (-1900 4075)(-2100 4075);
WIRE 16 -1 (-1900 4125)(-2100 4125);
WIRE 16 -1 (-2100 4175)(-2100 4125);
WIRE 16 -1 (-1900 4175)(-2100 4175);
WIRE 16 -1 (-2100 4225)(-2100 4175);
WIRE 16 -1 (-1900 4225)(-2100 4225);
WIRE 16 -1 (-2100 4275)(-2100 4225);
WIRE 16 -1 (-1900 4275)(-2100 4275);
WIRE 16 -1 (-2100 4325)(-2100 4275);
WIRE 16 -1 (-1900 4325)(-2100 4325);
WIRE 16 -1 (-2100 4375)(-2100 4325);
WIRE 16 -1 (-1900 4375)(-2100 4375);
WIRE 16 -1 (-2100 4425)(-2100 4375);
WIRE 16 -1 (-1900 4425)(-2100 4425);
WIRE 16 -1 (-2100 4475)(-2100 4425);
WIRE 16 -1 (-1900 4475)(-2100 4475);
WIRE 16 -1 (-2100 4525)(-2100 4475);
WIRE 16 -1 (-1900 4525)(-2100 4525);
WIRE 16 -1 (-2100 4575)(-2100 4525);
WIRE 16 -1 (-1900 4575)(-2100 4575);
WIRE 16 -1 (-2100 4625)(-2100 4575);
WIRE 16 -1 (-1900 4625)(-2100 4625);
WIRE 16 -1 (-2100 4675)(-2100 4625);
WIRE 16 -1 (-1900 4675)(-2100 4675);
WIRE 16 -1 (-2100 4725)(-2100 4675);
WIRE 16 -1 (-1900 4725)(-2100 4725);
WIRE 16 -1 (-2100 4775)(-2100 4725);
WIRE 16 -1 (-1900 4775)(-2100 4775);
WIRE 16 -1 (-2100 4825)(-2100 4775);
WIRE 16 -1 (-1900 4825)(-2100 4825);
WIRE 16 -1 (-2100 4875)(-2100 4825);
WIRE 16 -1 (-1900 4875)(-2100 4875);
WIRE 16 -1 (-2100 4925)(-2100 4875);
WIRE 16 -1 (-1900 4925)(-2100 4925);
WIRE 16 -1 (-2100 4975)(-2100 4925);
WIRE 16 -1 (-1900 4975)(-2100 4975);
WIRE 16 -1 (-2100 5025)(-2100 4975);
WIRE 16 -1 (-1900 5025)(-2100 5025);
WIRE 16 -1 (-2100 5075)(-2100 5025);
WIRE 16 -1 (-1900 5075)(-2100 5075);
WIRE 16 -1 (-2100 5125)(-2100 5075);
WIRE 16 -1 (-1900 5125)(-2100 5125);
WIRE 16 -1 (-2100 5175)(-2100 5125);
WIRE 16 -1 (-1900 5175)(-2100 5175);
WIRE 16 -1 (-2100 5225)(-2100 5175);
WIRE 16 -1 (-1900 5225)(-2100 5225);
WIRE 16 -1 (-2100 5275)(-2100 5225);
WIRE 16 -1 (-1900 5275)(-2100 5275);
WIRE 16 -1 (-2100 5325)(-2100 5275);
WIRE 16 -1 (-1900 5325)(-2100 5325);
WIRE 16 -1 (-1800 1450)(-1800 1375);
WIRE 16 -1 (-1800 1375)(-2350 1375);
WIRE 16 -1 (-5025 1400)(-4525 1400);
WIRE 16 -1 (-5025 1550)(-5025 1400);
WIRE 16 -1 (-2225 6300)(-2100 6300);
WIRE 16 -1 (-2225 6300)(-2225 6200);
WIRE 16 -1 (-2225 6300)(-2800 6300);
WIRE 16 -1 (-2100 5475)(-2100 6300);
WIRE 16 -1 (-1900 5475)(-2100 5475);
WIRE 16 -1 (-2100 5425)(-2100 5475);
WIRE 16 -1 (-2800 6200)(-2800 6300);
WIRE 16 -1 (-2800 6300)(-2800 6375);
WIRE 16 -1 (-1900 5425)(-2100 5425);
WIRE 16 -1 (-2100 5375)(-2100 5425);
WIRE 16 -1 (-1900 5375)(-2100 5375);
WIRE 16 -1 (-2225 5875)(-2225 6000);
WIRE 16 -1 (-2225 5875)(-2800 5875);
WIRE 16 -1 (-2800 5875)(-2800 6000);
WIRE 16 -1 (-2800 5875)(-2800 5800);
WIRE 16 -1 (-500 2325)(-500 2225);
WIRE 16 -1 (-500 2375)(-500 2325);
WIRE 16 -1 (-500 2325)(-700 2325);
WIRE 16 -1 (-500 2225)(-500 2175);
WIRE 16 -1 (-500 2225)(-700 2225);
WIRE 16 -1 (-500 2175)(-500 2125);
WIRE 16 -1 (-500 2175)(-700 2175);
WIRE 16 -1 (-500 2425)(-500 2375);
WIRE 16 -1 (-500 2375)(-700 2375);
WIRE 16 -1 (-500 2475)(-500 2425);
WIRE 16 -1 (-500 2425)(-700 2425);
WIRE 16 -1 (-500 2125)(-700 2125);
WIRE 16 -1 (-500 2125)(-500 1925);
WIRE 16 -1 (-500 2525)(-500 2475);
WIRE 16 -1 (-500 2475)(-700 2475);
WIRE 16 -1 (-500 2575)(-500 2525);
WIRE 16 -1 (-500 2525)(-700 2525);
WIRE 16 -1 (-500 2625)(-500 2575);
WIRE 16 -1 (-500 2575)(-700 2575);
WIRE 16 -1 (-500 2675)(-500 2625);
WIRE 16 -1 (-500 2625)(-700 2625);
WIRE 16 -1 (-500 2725)(-500 2675);
WIRE 16 -1 (-500 2675)(-700 2675);
WIRE 16 -1 (-500 2775)(-500 2725);
WIRE 16 -1 (-500 2725)(-700 2725);
WIRE 16 -1 (-500 2825)(-500 2775);
WIRE 16 -1 (-500 2775)(-700 2775);
WIRE 16 -1 (-500 2875)(-500 2825);
WIRE 16 -1 (-500 2825)(-700 2825);
WIRE 16 -1 (-500 2925)(-500 2875);
WIRE 16 -1 (-500 2875)(-700 2875);
WIRE 16 -1 (-500 2975)(-500 2925);
WIRE 16 -1 (-500 2925)(-700 2925);
WIRE 16 -1 (-500 3025)(-500 2975);
WIRE 16 -1 (-500 2975)(-700 2975);
WIRE 16 -1 (-500 3075)(-500 3025);
WIRE 16 -1 (-500 3025)(-700 3025);
WIRE 16 -1 (-500 3125)(-500 3075);
WIRE 16 -1 (-500 3075)(-700 3075);
WIRE 16 -1 (-500 3175)(-500 3125);
WIRE 16 -1 (-500 3125)(-700 3125);
WIRE 16 -1 (-500 3225)(-500 3175);
WIRE 16 -1 (-500 3175)(-700 3175);
WIRE 16 -1 (-500 3275)(-500 3225);
WIRE 16 -1 (-500 3225)(-700 3225);
WIRE 16 -1 (-500 3325)(-500 3275);
WIRE 16 -1 (-500 3275)(-700 3275);
WIRE 16 -1 (-500 3375)(-500 3325);
WIRE 16 -1 (-500 3325)(-700 3325);
WIRE 16 -1 (-500 3425)(-500 3375);
WIRE 16 -1 (-500 3375)(-700 3375);
WIRE 16 -1 (-500 3475)(-500 3425);
WIRE 16 -1 (-500 3425)(-700 3425);
WIRE 16 -1 (-500 3525)(-500 3475);
WIRE 16 -1 (-500 3475)(-700 3475);
WIRE 16 -1 (-500 3575)(-500 3525);
WIRE 16 -1 (-500 3525)(-700 3525);
WIRE 16 -1 (-500 3625)(-500 3575);
WIRE 16 -1 (-500 3575)(-700 3575);
WIRE 16 -1 (-500 3675)(-500 3625);
WIRE 16 -1 (-500 3625)(-700 3625);
WIRE 16 -1 (-500 3725)(-500 3675);
WIRE 16 -1 (-500 3675)(-700 3675);
WIRE 16 -1 (-500 3775)(-500 3725);
WIRE 16 -1 (-500 3725)(-700 3725);
WIRE 16 -1 (-500 3825)(-500 3775);
WIRE 16 -1 (-500 3775)(-700 3775);
WIRE 16 -1 (-500 3875)(-500 3825);
WIRE 16 -1 (-500 3825)(-700 3825);
WIRE 16 -1 (-500 3925)(-500 3875);
WIRE 16 -1 (-500 3875)(-700 3875);
WIRE 16 -1 (-500 3975)(-500 3925);
WIRE 16 -1 (-500 3925)(-700 3925);
WIRE 16 -1 (-500 4025)(-500 3975);
WIRE 16 -1 (-500 3975)(-700 3975);
WIRE 16 -1 (-500 4075)(-500 4025);
WIRE 16 -1 (-500 4025)(-700 4025);
WIRE 16 -1 (-500 4125)(-500 4075);
WIRE 16 -1 (-500 4075)(-700 4075);
WIRE 16 -1 (-500 4175)(-500 4125);
WIRE 16 -1 (-500 4125)(-700 4125);
WIRE 16 -1 (-500 4225)(-500 4175);
WIRE 16 -1 (-500 4175)(-700 4175);
WIRE 16 -1 (-500 4275)(-500 4225);
WIRE 16 -1 (-500 4225)(-700 4225);
WIRE 16 -1 (-500 4325)(-500 4275);
WIRE 16 -1 (-500 4275)(-700 4275);
WIRE 16 -1 (-500 4375)(-500 4325);
WIRE 16 -1 (-500 4325)(-700 4325);
WIRE 16 -1 (-500 4425)(-500 4375);
WIRE 16 -1 (-500 4375)(-700 4375);
WIRE 16 -1 (-500 4475)(-500 4425);
WIRE 16 -1 (-500 4425)(-700 4425);
WIRE 16 -1 (-500 4525)(-500 4475);
WIRE 16 -1 (-500 4475)(-700 4475);
WIRE 16 -1 (-500 4575)(-500 4525);
WIRE 16 -1 (-500 4525)(-700 4525);
WIRE 16 -1 (-500 4625)(-500 4575);
WIRE 16 -1 (-500 4575)(-700 4575);
WIRE 16 -1 (-500 4675)(-500 4625);
WIRE 16 -1 (-500 4625)(-700 4625);
WIRE 16 -1 (-500 4725)(-500 4675);
WIRE 16 -1 (-500 4675)(-700 4675);
WIRE 16 -1 (-500 4775)(-500 4725);
WIRE 16 -1 (-500 4725)(-700 4725);
WIRE 16 -1 (-500 4825)(-500 4775);
WIRE 16 -1 (-500 4775)(-700 4775);
WIRE 16 -1 (-500 4875)(-500 4825);
WIRE 16 -1 (-500 4825)(-700 4825);
WIRE 16 -1 (-500 4925)(-500 4875);
WIRE 16 -1 (-500 4875)(-700 4875);
WIRE 16 -1 (-500 4975)(-500 4925);
WIRE 16 -1 (-500 4925)(-700 4925);
WIRE 16 -1 (-500 5025)(-500 4975);
WIRE 16 -1 (-500 4975)(-700 4975);
WIRE 16 -1 (-500 5075)(-500 5025);
WIRE 16 -1 (-500 5025)(-700 5025);
WIRE 16 -1 (-500 5125)(-500 5075);
WIRE 16 -1 (-500 5075)(-700 5075);
WIRE 16 -1 (-500 5175)(-500 5125);
WIRE 16 -1 (-500 5125)(-700 5125);
WIRE 16 -1 (-500 5225)(-500 5175);
WIRE 16 -1 (-500 5175)(-700 5175);
WIRE 16 -1 (-500 5275)(-500 5225);
WIRE 16 -1 (-500 5225)(-700 5225);
WIRE 16 -1 (-500 5325)(-500 5275);
WIRE 16 -1 (-500 5275)(-700 5275);
WIRE 16 -1 (-500 5375)(-500 5325);
WIRE 16 -1 (-500 5325)(-700 5325);
WIRE 16 -1 (-500 5425)(-500 5375);
WIRE 16 -1 (-500 5375)(-700 5375);
WIRE 16 -1 (-500 5475)(-500 5425);
WIRE 16 -1 (-500 5425)(-700 5425);
WIRE 16 -1 (-500 5475)(-700 5475);
WIRE 16 -1 (-2475 925)(-1425 925);
FORCEPROP 2 LAST SIG_NAME PWRGD_CHAF_CPU1_R2
J 0
(-2110 935);
DISPLAY 0.680851 (-2110 935);
WIRE 16 -1 (-6125 1475)(-6125 1400);
WIRE 16 -1 (-6125 1475)(-6850 1475);
FORCEPROP 2 LAST SIG_NAME PD_CHA_CPU1_DIMM0_SAA
J 0
(-6835 1485);
DISPLAY 0.489362 (-6835 1485);
WIRE 16 -1 (-6000 5475)(-5800 5475);
WIRE 16 -1 (-7200 4075)(-7400 4075);
WIRE 16 -1 (-7200 3925)(-7400 3925);
WIRE 16 -1 (-7200 4775)(-7400 4775);
WIRE 16 -1 (-7200 4825)(-7400 4825);
WIRE 16 -1 (-7200 5275)(-7400 5275);
WIRE 16 -1 (-7200 4875)(-7400 4875);
WIRE 16 -1 (-7200 4925)(-7400 4925);
WIRE 16 -1 (-7200 5375)(-7400 5375);
WIRE 16 -1 (-7200 4975)(-7400 4975);
WIRE 16 -1 (-7200 5425)(-7400 5425);
WIRE 16 -1 (-7200 5025)(-7400 5025);
WIRE 16 -1 (-7200 5075)(-7400 5075);
WIRE 16 -1 (-7200 4025)(-7400 4025);
WIRE 16 -1 (-7200 3975)(-7400 3975);
WIRE 16 -1 (-7200 3875)(-7400 3875);
WIRE 16 -1 (-7200 3825)(-7400 3825);
WIRE 16 -1 (-7200 3375)(-7400 3375);
WIRE 16 -1 (-7200 3325)(-7400 3325);
WIRE 16 -1 (-7200 3275)(-7400 3275);
WIRE 16 -1 (-7200 4175)(-8000 4175);
FORCEPROP 2 LAST SIG_NAME M_A_CPU1_CLK_DN<0>
J 0
(-8000 4185);
DISPLAY 0.489362 (-8000 4185);
WIRE 16 -1 (-7200 4225)(-8000 4225);
FORCEPROP 2 LAST SIG_NAME M_A_CPU1_CLK_DP<0>
J 0
(-8000 4235);
DISPLAY 0.489362 (-8000 4235);
WIRE 16 -1 (-7200 4325)(-8000 4325);
FORCEPROP 2 LAST SIG_NAME M_A_CPU1_SB_CS_N<0>
J 0
(-8000 4335);
DISPLAY 0.489362 (-8000 4335);
WIRE 16 -1 (-7200 4525)(-8000 4525);
FORCEPROP 2 LAST SIG_NAME M_A_CPU1_SA_CS_N<1>
J 0
(-8000 4535);
DISPLAY 0.489362 (-8000 4535);
WIRE 16 -1 (-7200 4375)(-8000 4375);
FORCEPROP 2 LAST SIG_NAME M_A_CPU1_SB_CS_N<1>
J 0
(-8000 4385);
DISPLAY 0.489362 (-8000 4385);
WIRE 16 -1 (-5800 5425)(-6000 5425);
WIRE 16 -1 (-5800 5375)(-6000 5375);
WIRE 16 -1 (-5800 5225)(-6000 5225);
WIRE 16 -1 (-5800 5175)(-6000 5175);
WIRE 16 -1 (-6000 5075)(-5800 5075);
WIRE 16 -1 (-5800 4925)(-6000 4925);
WIRE 16 -1 (-6000 4875)(-5800 4875);
WIRE 16 -1 (-5800 4725)(-6000 4725);
WIRE 16 -1 (-6000 4675)(-5800 4675);
WIRE 16 -1 (-5800 4625)(-6000 4625);
WIRE 16 -1 (-5800 4575)(-6000 4575);
WIRE 16 -1 (-5800 4525)(-6000 4525);
WIRE 16 -1 (-6000 4475)(-5800 4475);
WIRE 16 -1 (-5800 4425)(-6000 4425);
WIRE 16 -1 (-5800 4375)(-6000 4375);
WIRE 16 -1 (-5800 4325)(-6000 4325);
WIRE 16 -1 (-6000 4275)(-5800 4275);
WIRE 16 -1 (-5800 4225)(-6000 4225);
WIRE 16 -1 (-5800 4175)(-6000 4175);
WIRE 16 -1 (-5800 4125)(-6000 4125);
WIRE 16 -1 (-6000 4075)(-5800 4075);
WIRE 16 -1 (-5800 4025)(-6000 4025);
WIRE 16 -1 (-5800 3975)(-6000 3975);
WIRE 16 -1 (-5800 3925)(-6000 3925);
WIRE 16 -1 (-6000 3825)(-5800 3825);
WIRE 16 -1 (-5800 3675)(-6000 3675);
WIRE 16 -1 (-6000 3625)(-5800 3625);
WIRE 16 -1 (-5800 3575)(-6000 3575);
WIRE 16 -1 (-5800 3525)(-6000 3525);
WIRE 16 -1 (-5800 3475)(-6000 3475);
WIRE 16 -1 (-6000 3425)(-5800 3425);
WIRE 16 -1 (-5800 3375)(-6000 3375);
WIRE 16 -1 (-5800 3275)(-6000 3275);
WIRE 16 -1 (-6000 3225)(-5800 3225);
WIRE 16 -1 (-5800 3175)(-6000 3175);
WIRE 16 -1 (-5800 3125)(-6000 3125);
WIRE 16 -1 (-5800 3075)(-6000 3075);
WIRE 16 -1 (-6000 3025)(-5800 3025);
WIRE 16 -1 (-5800 2975)(-6000 2975);
WIRE 16 -1 (-5800 2925)(-6000 2925);
WIRE 16 -1 (-5800 2875)(-6000 2875);
WIRE 16 -1 (-6000 2825)(-5800 2825);
WIRE 16 -1 (-5800 2775)(-6000 2775);
WIRE 16 -1 (-5800 2725)(-6000 2725);
WIRE 16 -1 (-5800 2675)(-6000 2675);
WIRE 16 -1 (-6000 2625)(-5800 2625);
WIRE 16 -1 (-6000 2425)(-5800 2425);
WIRE 16 -1 (-5800 2375)(-6000 2375);
WIRE 16 -1 (-5800 2325)(-6000 2325);
WIRE 16 -1 (-5800 2275)(-6000 2275);
WIRE 16 -1 (-7200 2075)(-8000 2075);
FORCEPROP 2 LAST SIG_NAME M_A_CPU1_SA_RSP<0>
J 0
(-8000 2085);
DISPLAY 0.489362 (-8000 2085);
WIRE 16 -1 (-7200 4675)(-8000 4675);
FORCEPROP 2 LAST SIG_NAME M_A_CPU1_SA_PAR
J 0
(-8000 4685);
DISPLAY 0.489362 (-8000 4685);
WIRE 16 -1 (-7200 4625)(-8000 4625);
FORCEPROP 2 LAST SIG_NAME M_A_CPU1_SB_PAR
J 0
(-8000 4635);
DISPLAY 0.489362 (-8000 4635);
WIRE 16 -1 (-5800 5325)(-6000 5325);
WIRE 16 -1 (-6000 5275)(-5800 5275);
WIRE 16 -1 (-7200 5175)(-7400 5175);
WIRE 16 -1 (-5800 5125)(-6000 5125);
WIRE 16 -1 (-5800 4825)(-6000 4825);
WIRE 16 -1 (-5800 4775)(-6000 4775);
WIRE 16 -1 (-3475 4350)(-3075 4350);
WIRE 16 -1 (-3275 4300)(-3475 4300);
WIRE 16 -1 (-3275 3450)(-3475 3450);
WIRE 16 -1 (-3475 3400)(-3075 3400);
WIRE 16 -1 (-3275 3350)(-3475 3350);
WIRE 16 -1 (-3475 3650)(-3075 3650);
WIRE 16 -1 (-3275 3700)(-3475 3700);
WIRE 16 -1 (-3475 2600)(-3075 2600);
WIRE 16 -1 (-3275 2650)(-3475 2650);
WIRE 16 -1 (-3475 3750)(-3075 3750);
WIRE 16 -1 (-3475 3800)(-3275 3800);
WIRE 16 -1 (-3475 2700)(-3075 2700);
WIRE 16 -1 (-3475 2750)(-3275 2750);
WIRE 16 -1 (-3475 3850)(-3075 3850);
WIRE 16 -1 (-3275 3900)(-3475 3900);
WIRE 16 -1 (-3475 2800)(-3075 2800);
WIRE 16 -1 (-3275 2850)(-3475 2850);
WIRE 16 -1 (-3475 3950)(-3075 3950);
WIRE 16 -1 (-3275 4000)(-3475 4000);
WIRE 16 -1 (-3475 2900)(-3075 2900);
WIRE 16 -1 (-3275 2950)(-3475 2950);
WIRE 16 -1 (-3075 4050)(-3475 4050);
WIRE 16 -1 (-3275 4100)(-3475 4100);
WIRE 16 -1 (-3475 3000)(-3075 3000);
WIRE 16 -1 (-3275 3050)(-3475 3050);
WIRE 16 -1 (-3475 4150)(-3075 4150);
WIRE 16 -1 (-3475 4200)(-3275 4200);
WIRE 16 -1 (-3475 3100)(-3075 3100);
WIRE 16 -1 (-3475 3150)(-3275 3150);
WIRE 16 -1 (-3475 4250)(-3075 4250);
WIRE 16 -1 (-3475 3200)(-3075 3200);
WIRE 16 -1 (-3275 3250)(-3475 3250);
WIRE 16 -1 (-3275 4400)(-3475 4400);
WIRE 16 -1 (-3475 3300)(-3075 3300);
WIRE 16 -1 (-3475 4450)(-3075 4450);
WIRE 16 -1 (-3275 4500)(-3475 4500);
WIRE 16 -1 (-3475 4550)(-3075 4550);
WIRE 16 -1 (-3475 3500)(-3075 3500);
WIRE 16 -1 (-3475 3550)(-3275 3550);
WIRE 16 -1 (-5800 5025)(-6000 5025);
WIRE 16 -1 (-5800 4975)(-6000 4975);
WIRE 16 -1 (-3475 4600)(-3275 4600);
WIRE 16 -1 (-7200 5225)(-7400 5225);
WIRE 16 -1 (-7200 5325)(-7400 5325);
WIRE 16 -1 (-7200 5475)(-7400 5475);
WIRE 16 -1 (-5800 3325)(-6000 3325);
WIRE 16 -1 (-5800 2525)(-6000 2525);
WIRE 16 -1 (-5800 2575)(-6000 2575);
WIRE 16 -1 (-5800 2475)(-6000 2475);
WIRE 16 -1 (-8525 2275)(-8525 2225);
WIRE 16 -1 (-8500 2225)(-8525 2225);
WIRE 16 -1 (-8525 2225)(-8900 2225);
FORCEPROP 2 LAST SIG_NAME PWRGD_CHAF_CPU1
J 0
(-8935 2235);
DISPLAY 0.489362 (-8935 2235);
DOT 1 (-2100 4425);
DOT 1 (-2225 6300);
DOT 1 (-2800 6300);
DOT 1 (-2800 5875);
DOT 1 (-500 5425);
DOT 1 (-500 5375);
DOT 1 (-500 5275);
DOT 1 (-500 5325);
DOT 1 (-500 5225);
DOT 1 (-500 5175);
DOT 1 (-500 5125);
DOT 1 (-500 5075);
DOT 1 (-500 5025);
DOT 1 (-500 4975);
DOT 1 (-500 4925);
DOT 1 (-500 4875);
DOT 1 (-500 4825);
DOT 1 (-500 4775);
DOT 1 (-500 4725);
DOT 1 (-500 4625);
DOT 1 (-500 4675);
DOT 1 (-500 4575);
DOT 1 (-500 4525);
DOT 1 (-500 4475);
DOT 1 (-500 4425);
DOT 1 (-500 4375);
DOT 1 (-500 4325);
DOT 1 (-500 4275);
DOT 1 (-500 4225);
DOT 1 (-500 4175);
DOT 1 (-500 4125);
DOT 1 (-500 4075);
DOT 1 (-500 4025);
DOT 1 (-500 3975);
DOT 1 (-500 3925);
DOT 1 (-500 3875);
DOT 1 (-500 3825);
DOT 1 (-500 3775);
DOT 1 (-500 3725);
DOT 1 (-2100 5425);
DOT 1 (-2100 5475);
DOT 1 (-2100 5275);
DOT 1 (-2100 5225);
DOT 1 (-2100 5175);
DOT 1 (-2100 5025);
DOT 1 (-2100 5075);
DOT 1 (-2100 4975);
DOT 1 (-2100 4925);
DOT 1 (-2100 4875);
DOT 1 (-2100 4825);
DOT 1 (-2100 4775);
DOT 1 (-2100 4725);
DOT 1 (-2100 4625);
DOT 1 (-2100 4675);
DOT 1 (-2100 4575);
DOT 1 (-2100 4525);
DOT 1 (-2100 4475);
DOT 1 (-2100 4375);
DOT 1 (-2100 4325);
DOT 1 (-2100 4275);
DOT 1 (-2100 4225);
DOT 1 (-2100 4125);
DOT 1 (-2100 4175);
DOT 1 (-2100 4075);
DOT 1 (-2100 4025);
DOT 1 (-2100 3975);
DOT 1 (-2100 3925);
DOT 1 (-2100 3875);
DOT 1 (-2100 3825);
DOT 1 (-2100 3725);
DOT 1 (-2100 3775);
DOT 1 (-500 3675);
DOT 1 (-500 3625);
DOT 1 (-500 3575);
DOT 1 (-500 3525);
DOT 1 (-500 3475);
DOT 1 (-500 3425);
DOT 1 (-500 3375);
DOT 1 (-500 3325);
DOT 1 (-500 3225);
DOT 1 (-500 3275);
DOT 1 (-500 3175);
DOT 1 (-500 3125);
DOT 1 (-500 3075);
DOT 1 (-500 3025);
DOT 1 (-500 2975);
DOT 1 (-500 2925);
DOT 1 (-500 2875);
DOT 1 (-500 2825);
DOT 1 (-500 2775);
DOT 1 (-500 2725);
DOT 1 (-500 2675);
DOT 1 (-500 2575);
DOT 1 (-500 2625);
DOT 1 (-500 2525);
DOT 1 (-500 2475);
DOT 1 (-500 2425);
DOT 1 (-500 2375);
DOT 1 (-500 2325);
DOT 1 (-500 2225);
DOT 1 (-500 2175);
DOT 1 (-500 2125);
DOT 1 (-2100 3675);
DOT 1 (-2100 3625);
DOT 1 (-2100 3575);
DOT 1 (-2100 3475);
DOT 1 (-2100 3525);
DOT 1 (-2100 3425);
DOT 1 (-2100 3375);
DOT 1 (-2100 3325);
DOT 1 (-2100 3225);
DOT 1 (-2100 3275);
DOT 1 (-2100 3175);
DOT 1 (-2100 3125);
DOT 1 (-2100 3075);
DOT 1 (-2100 3025);
DOT 1 (-2100 2975);
DOT 1 (-2100 2925);
DOT 1 (-2100 2875);
DOT 1 (-2100 2825);
DOT 1 (-2100 2775);
DOT 1 (-2100 2725);
DOT 1 (-2100 2675);
DOT 1 (-2100 2625);
DOT 1 (-2100 2575);
DOT 1 (-2100 2525);
DOT 1 (-2100 2475);
DOT 1 (-2100 2425);
DOT 1 (-2100 2375);
DOT 1 (-2100 2325);
DOT 1 (-8500 3450);
DOT 1 (-8275 2225);
DOT 1 (-8525 2225);
DOT 1 (-2100 5125);
DOT 1 (-3750 925);
DOT 1 (-2100 2275);
DOT 1 (-2100 2225);
DOT 1 (-2775 925);
QUIT
